FILE_TYPE = MACRO_DRAWING;
SET COLOR_WIRE YELLOW;
SET COLOR_PROP MONO;
SET COLOR_DOT WHITE;
SET COLOR_ARC YELLOW;
SET COLOR_BODY GREEN;
SET COLOR_NOTE MONO;
SET PROP_DISPLAY VALUE;
SET PAGE_NUMBER P61;
FORCEADD OFFPAGE..5
(-6425 525);
FORCEPROP 2 LAST $XR0 85 
J 0
(-6679 525);
DISPLAY 0.638298 (-6679 525);
PAINT MONO (-6679 525);
FORCEPROP 2 LAST $XR1 86 
J 0
(-6769 525);
DISPLAY 0.638298 (-6769 525);
PAINT MONO (-6769 525);
FORCEPROP 2 LAST CDS_LIB mstr_standard
J 0
(-6425 525);
PAINT MONO (-6425 525);
DISPLAY INVISIBLE (-6425 525);
FORCEPROP 1 LAST OFFPAGE TRUE
J 0
(-6100 400);
DISPLAY 1.170213 (-6100 400);
PAINT GREEN (-6100 400);
DISPLAY INVISIBLE (-6100 400);
FORCEPROP 1 LAST COMMENT_BODY TRUE
J 0
(-6325 450);
DISPLAY 1.170213 (-6325 450);
PAINT GREEN (-6325 450);
DISPLAY INVISIBLE (-6325 450);
FORCEPROP 2 LAST PATH I1
J 0
(-6375 600);
DISPLAY 1.021277 (-6375 600);
PAINT ORANGE (-6375 600);
DISPLAY INVISIBLE (-6375 600);
FORCEADD TAP..6
(-5575 825);
FORCEPROP 3 LASTPIN (-5525 825) SIG_NAME M_L_CLK_DP<0>
J 0
(-5515 835);
DISPLAY 0.659574 (-5515 835);
PAINT MONO (-5515 835);
DISPLAY INVISIBLE (-5515 835);
FORCEPROP 1 LASTPIN (-5525 825) BN 0
J 0
(-5577 833);
DISPLAY 0.617021 (-5577 833);
PAINT GREEN (-5577 833);
FORCEPROP 2 LAST CDS_LIB mstr_standard
J 0
(-5575 825);
PAINT MONO (-5575 825);
DISPLAY INVISIBLE (-5575 825);
FORCEPROP 1 LAST BODY_TYPE PLUMBING
J 0
(-5575 775);
DISPLAY 1.595745 (-5575 775);
PAINT GREEN (-5575 775);
DISPLAY INVISIBLE (-5575 775);
FORCEPROP 1 LAST HDL_TAP TRUE
J 0
(-5250 700);
DISPLAY 1.595745 (-5250 700);
PAINT GREEN (-5250 700);
DISPLAY INVISIBLE (-5250 700);
FORCEPROP 1 LAST PATH I10
J 0
(-5577 825);
DISPLAY 0.872340 (-5577 825);
PAINT GREEN (-5577 825);
DISPLAY INVISIBLE (-5577 825);
FORCEADD TAP..6
R 2
(-2850 1575);
FORCEPROP 3 LASTPIN (-2900 1575) SIG_NAME M_L_ODT<3>
J 0
(-2890 1585);
DISPLAY 0.659574 (-2890 1585);
PAINT MONO (-2890 1585);
DISPLAY INVISIBLE (-2890 1585);
FORCEPROP 1 LASTPIN (-2900 1575) BN 3
J 2
(-2848 1583);
DISPLAY 0.617021 (-2848 1583);
PAINT GREEN (-2848 1583);
FORCEPROP 2 LAST CDS_LIB mstr_standard
J 0
(-2850 1575);
PAINT MONO (-2850 1575);
DISPLAY INVISIBLE (-2850 1575);
FORCEPROP 1 LAST BODY_TYPE PLUMBING
J 2
(-2850 1525);
DISPLAY 1.595745 (-2850 1525);
PAINT GREEN (-2850 1525);
DISPLAY INVISIBLE (-2850 1525);
FORCEPROP 1 LAST HDL_TAP TRUE
J 2
(-3175 1450);
DISPLAY 1.595745 (-3175 1450);
PAINT GREEN (-3175 1450);
DISPLAY INVISIBLE (-3175 1450);
FORCEPROP 1 LAST PATH I100
J 2
(-2848 1575);
DISPLAY 0.872340 (-2848 1575);
PAINT GREEN (-2848 1575);
DISPLAY INVISIBLE (-2848 1575);
FORCEADD TAP..6
R 2
(-2850 1525);
FORCEPROP 3 LASTPIN (-2900 1525) SIG_NAME M_L_ODT<2>
J 0
(-2890 1535);
DISPLAY 0.659574 (-2890 1535);
PAINT MONO (-2890 1535);
DISPLAY INVISIBLE (-2890 1535);
FORCEPROP 1 LASTPIN (-2900 1525) BN 2
J 2
(-2848 1533);
DISPLAY 0.617021 (-2848 1533);
PAINT GREEN (-2848 1533);
FORCEPROP 2 LAST CDS_LIB mstr_standard
J 0
(-2850 1525);
PAINT MONO (-2850 1525);
DISPLAY INVISIBLE (-2850 1525);
FORCEPROP 1 LAST BODY_TYPE PLUMBING
J 2
(-2850 1475);
DISPLAY 1.595745 (-2850 1475);
PAINT GREEN (-2850 1475);
DISPLAY INVISIBLE (-2850 1475);
FORCEPROP 1 LAST HDL_TAP TRUE
J 2
(-3175 1400);
DISPLAY 1.595745 (-3175 1400);
PAINT GREEN (-3175 1400);
DISPLAY INVISIBLE (-3175 1400);
FORCEPROP 1 LAST PATH I101
J 2
(-2848 1525);
DISPLAY 0.872340 (-2848 1525);
PAINT GREEN (-2848 1525);
DISPLAY INVISIBLE (-2848 1525);
FORCEADD TAP..6
R 2
(-2850 1475);
FORCEPROP 3 LASTPIN (-2900 1475) SIG_NAME M_L_ODT<1>
J 0
(-2890 1485);
DISPLAY 0.659574 (-2890 1485);
PAINT MONO (-2890 1485);
DISPLAY INVISIBLE (-2890 1485);
FORCEPROP 1 LASTPIN (-2900 1475) BN 1
J 2
(-2848 1483);
DISPLAY 0.617021 (-2848 1483);
PAINT GREEN (-2848 1483);
FORCEPROP 2 LAST CDS_LIB mstr_standard
J 0
(-2850 1475);
PAINT MONO (-2850 1475);
DISPLAY INVISIBLE (-2850 1475);
FORCEPROP 1 LAST BODY_TYPE PLUMBING
J 2
(-2850 1425);
DISPLAY 1.595745 (-2850 1425);
PAINT GREEN (-2850 1425);
DISPLAY INVISIBLE (-2850 1425);
FORCEPROP 1 LAST HDL_TAP TRUE
J 2
(-3175 1350);
DISPLAY 1.595745 (-3175 1350);
PAINT GREEN (-3175 1350);
DISPLAY INVISIBLE (-3175 1350);
FORCEPROP 1 LAST PATH I102
J 2
(-2848 1475);
DISPLAY 0.872340 (-2848 1475);
PAINT GREEN (-2848 1475);
DISPLAY INVISIBLE (-2848 1475);
FORCEADD TAP..6
R 2
(-2850 1675);
FORCEPROP 3 LASTPIN (-2900 1675) SIG_NAME M_L_CKE<0>
J 0
(-2890 1685);
DISPLAY 0.659574 (-2890 1685);
PAINT MONO (-2890 1685);
DISPLAY INVISIBLE (-2890 1685);
FORCEPROP 1 LASTPIN (-2900 1675) BN 0
J 2
(-2848 1683);
DISPLAY 0.617021 (-2848 1683);
PAINT GREEN (-2848 1683);
FORCEPROP 2 LAST CDS_LIB mstr_standard
J 0
(-2850 1675);
PAINT MONO (-2850 1675);
DISPLAY INVISIBLE (-2850 1675);
FORCEPROP 1 LAST BODY_TYPE PLUMBING
J 2
(-2850 1625);
DISPLAY 1.595745 (-2850 1625);
PAINT GREEN (-2850 1625);
DISPLAY INVISIBLE (-2850 1625);
FORCEPROP 1 LAST HDL_TAP TRUE
J 2
(-3175 1550);
DISPLAY 1.595745 (-3175 1550);
PAINT GREEN (-3175 1550);
DISPLAY INVISIBLE (-3175 1550);
FORCEPROP 1 LAST PATH I103
J 2
(-2848 1675);
DISPLAY 0.872340 (-2848 1675);
PAINT GREEN (-2848 1675);
DISPLAY INVISIBLE (-2848 1675);
FORCEADD TAP..6
R 2
(-2850 1725);
FORCEPROP 3 LASTPIN (-2900 1725) SIG_NAME M_L_CKE<1>
J 0
(-2890 1735);
DISPLAY 0.659574 (-2890 1735);
PAINT MONO (-2890 1735);
DISPLAY INVISIBLE (-2890 1735);
FORCEPROP 1 LASTPIN (-2900 1725) BN 1
J 2
(-2848 1733);
DISPLAY 0.617021 (-2848 1733);
PAINT GREEN (-2848 1733);
FORCEPROP 2 LAST CDS_LIB mstr_standard
J 0
(-2850 1725);
PAINT MONO (-2850 1725);
DISPLAY INVISIBLE (-2850 1725);
FORCEPROP 1 LAST BODY_TYPE PLUMBING
J 2
(-2850 1675);
DISPLAY 1.595745 (-2850 1675);
PAINT GREEN (-2850 1675);
DISPLAY INVISIBLE (-2850 1675);
FORCEPROP 1 LAST HDL_TAP TRUE
J 2
(-3175 1600);
DISPLAY 1.595745 (-3175 1600);
PAINT GREEN (-3175 1600);
DISPLAY INVISIBLE (-3175 1600);
FORCEPROP 1 LAST PATH I104
J 2
(-2848 1725);
DISPLAY 0.872340 (-2848 1725);
PAINT GREEN (-2848 1725);
DISPLAY INVISIBLE (-2848 1725);
FORCEADD TAP..6
R 2
(-2850 1775);
FORCEPROP 3 LASTPIN (-2900 1775) SIG_NAME M_L_CKE<2>
J 0
(-2890 1785);
DISPLAY 0.659574 (-2890 1785);
PAINT MONO (-2890 1785);
DISPLAY INVISIBLE (-2890 1785);
FORCEPROP 1 LASTPIN (-2900 1775) BN 2
J 2
(-2848 1783);
DISPLAY 0.617021 (-2848 1783);
PAINT GREEN (-2848 1783);
FORCEPROP 2 LAST CDS_LIB mstr_standard
J 0
(-2850 1775);
PAINT MONO (-2850 1775);
DISPLAY INVISIBLE (-2850 1775);
FORCEPROP 1 LAST BODY_TYPE PLUMBING
J 2
(-2850 1725);
DISPLAY 1.595745 (-2850 1725);
PAINT GREEN (-2850 1725);
DISPLAY INVISIBLE (-2850 1725);
FORCEPROP 1 LAST HDL_TAP TRUE
J 2
(-3175 1650);
DISPLAY 1.595745 (-3175 1650);
PAINT GREEN (-3175 1650);
DISPLAY INVISIBLE (-3175 1650);
FORCEPROP 1 LAST PATH I105
J 2
(-2848 1775);
DISPLAY 0.872340 (-2848 1775);
PAINT GREEN (-2848 1775);
DISPLAY INVISIBLE (-2848 1775);
FORCEADD TAP..6
R 2
(-2850 1825);
FORCEPROP 3 LASTPIN (-2900 1825) SIG_NAME M_L_CKE<3>
J 0
(-2890 1835);
DISPLAY 0.659574 (-2890 1835);
PAINT MONO (-2890 1835);
DISPLAY INVISIBLE (-2890 1835);
FORCEPROP 1 LASTPIN (-2900 1825) BN 3
J 2
(-2848 1833);
DISPLAY 0.617021 (-2848 1833);
PAINT GREEN (-2848 1833);
FORCEPROP 2 LAST CDS_LIB mstr_standard
J 0
(-2850 1825);
PAINT MONO (-2850 1825);
DISPLAY INVISIBLE (-2850 1825);
FORCEPROP 1 LAST BODY_TYPE PLUMBING
J 2
(-2850 1775);
DISPLAY 1.595745 (-2850 1775);
PAINT GREEN (-2850 1775);
DISPLAY INVISIBLE (-2850 1775);
FORCEPROP 1 LAST HDL_TAP TRUE
J 2
(-3175 1700);
DISPLAY 1.595745 (-3175 1700);
PAINT GREEN (-3175 1700);
DISPLAY INVISIBLE (-3175 1700);
FORCEPROP 1 LAST PATH I106
J 2
(-2848 1825);
DISPLAY 0.872340 (-2848 1825);
PAINT GREEN (-2848 1825);
DISPLAY INVISIBLE (-2848 1825);
FORCEADD TAP..6
R 2
(-2850 1925);
FORCEPROP 3 LASTPIN (-2900 1925) SIG_NAME M_L_MA<0>
J 0
(-2890 1935);
DISPLAY 0.659574 (-2890 1935);
PAINT MONO (-2890 1935);
DISPLAY INVISIBLE (-2890 1935);
FORCEPROP 1 LASTPIN (-2900 1925) BN 0
J 2
(-2848 1933);
DISPLAY 0.617021 (-2848 1933);
PAINT GREEN (-2848 1933);
FORCEPROP 2 LAST CDS_LIB mstr_standard
J 0
(-2850 1925);
PAINT MONO (-2850 1925);
DISPLAY INVISIBLE (-2850 1925);
FORCEPROP 1 LAST BODY_TYPE PLUMBING
J 2
(-2850 1875);
DISPLAY 1.595745 (-2850 1875);
PAINT GREEN (-2850 1875);
DISPLAY INVISIBLE (-2850 1875);
FORCEPROP 1 LAST HDL_TAP TRUE
J 2
(-3175 1800);
DISPLAY 1.595745 (-3175 1800);
PAINT GREEN (-3175 1800);
DISPLAY INVISIBLE (-3175 1800);
FORCEPROP 1 LAST PATH I107
J 2
(-2848 1925);
DISPLAY 0.872340 (-2848 1925);
PAINT GREEN (-2848 1925);
DISPLAY INVISIBLE (-2848 1925);
FORCEADD TAP..6
R 2
(-2850 1975);
FORCEPROP 3 LASTPIN (-2900 1975) SIG_NAME M_L_MA<1>
J 0
(-2890 1985);
DISPLAY 0.659574 (-2890 1985);
PAINT MONO (-2890 1985);
DISPLAY INVISIBLE (-2890 1985);
FORCEPROP 1 LASTPIN (-2900 1975) BN 1
J 2
(-2848 1983);
DISPLAY 0.617021 (-2848 1983);
PAINT GREEN (-2848 1983);
FORCEPROP 2 LAST CDS_LIB mstr_standard
J 0
(-2850 1975);
PAINT MONO (-2850 1975);
DISPLAY INVISIBLE (-2850 1975);
FORCEPROP 1 LAST BODY_TYPE PLUMBING
J 2
(-2850 1925);
DISPLAY 1.595745 (-2850 1925);
PAINT GREEN (-2850 1925);
DISPLAY INVISIBLE (-2850 1925);
FORCEPROP 1 LAST HDL_TAP TRUE
J 2
(-3175 1850);
DISPLAY 1.595745 (-3175 1850);
PAINT GREEN (-3175 1850);
DISPLAY INVISIBLE (-3175 1850);
FORCEPROP 1 LAST PATH I108
J 2
(-2848 1975);
DISPLAY 0.872340 (-2848 1975);
PAINT GREEN (-2848 1975);
DISPLAY INVISIBLE (-2848 1975);
FORCEADD TAP..6
R 2
(-2850 2075);
FORCEPROP 3 LASTPIN (-2900 2075) SIG_NAME M_L_MA<3>
J 0
(-2890 2085);
DISPLAY 0.659574 (-2890 2085);
PAINT MONO (-2890 2085);
DISPLAY INVISIBLE (-2890 2085);
FORCEPROP 1 LASTPIN (-2900 2075) BN 3
J 2
(-2848 2083);
DISPLAY 0.617021 (-2848 2083);
PAINT GREEN (-2848 2083);
FORCEPROP 2 LAST CDS_LIB mstr_standard
J 0
(-2850 2075);
PAINT MONO (-2850 2075);
DISPLAY INVISIBLE (-2850 2075);
FORCEPROP 1 LAST BODY_TYPE PLUMBING
J 2
(-2850 2025);
DISPLAY 1.595745 (-2850 2025);
PAINT GREEN (-2850 2025);
DISPLAY INVISIBLE (-2850 2025);
FORCEPROP 1 LAST HDL_TAP TRUE
J 2
(-3175 1950);
DISPLAY 1.595745 (-3175 1950);
PAINT GREEN (-3175 1950);
DISPLAY INVISIBLE (-3175 1950);
FORCEPROP 1 LAST PATH I109
J 2
(-2848 2075);
DISPLAY 0.872340 (-2848 2075);
PAINT GREEN (-2848 2075);
DISPLAY INVISIBLE (-2848 2075);
FORCEADD TAP..6
(-5575 925);
FORCEPROP 3 LASTPIN (-5525 925) SIG_NAME M_L_CLK_DP<2>
J 0
(-5515 935);
DISPLAY 0.659574 (-5515 935);
PAINT MONO (-5515 935);
DISPLAY INVISIBLE (-5515 935);
FORCEPROP 1 LASTPIN (-5525 925) BN 2
J 0
(-5577 933);
DISPLAY 0.617021 (-5577 933);
PAINT GREEN (-5577 933);
FORCEPROP 2 LAST CDS_LIB mstr_standard
J 0
(-5575 925);
PAINT MONO (-5575 925);
DISPLAY INVISIBLE (-5575 925);
FORCEPROP 1 LAST BODY_TYPE PLUMBING
J 0
(-5575 875);
DISPLAY 1.595745 (-5575 875);
PAINT GREEN (-5575 875);
DISPLAY INVISIBLE (-5575 875);
FORCEPROP 1 LAST HDL_TAP TRUE
J 0
(-5250 800);
DISPLAY 1.595745 (-5250 800);
PAINT GREEN (-5250 800);
DISPLAY INVISIBLE (-5250 800);
FORCEPROP 1 LAST PATH I11
J 0
(-5577 925);
DISPLAY 0.872340 (-5577 925);
PAINT GREEN (-5577 925);
DISPLAY INVISIBLE (-5577 925);
FORCEADD TAP..6
R 2
(-2850 2025);
FORCEPROP 3 LASTPIN (-2900 2025) SIG_NAME M_L_MA<2>
J 0
(-2890 2035);
DISPLAY 0.659574 (-2890 2035);
PAINT MONO (-2890 2035);
DISPLAY INVISIBLE (-2890 2035);
FORCEPROP 1 LASTPIN (-2900 2025) BN 2
J 2
(-2848 2033);
DISPLAY 0.617021 (-2848 2033);
PAINT GREEN (-2848 2033);
FORCEPROP 2 LAST CDS_LIB mstr_standard
J 0
(-2850 2025);
PAINT MONO (-2850 2025);
DISPLAY INVISIBLE (-2850 2025);
FORCEPROP 1 LAST BODY_TYPE PLUMBING
J 2
(-2850 1975);
DISPLAY 1.595745 (-2850 1975);
PAINT GREEN (-2850 1975);
DISPLAY INVISIBLE (-2850 1975);
FORCEPROP 1 LAST HDL_TAP TRUE
J 2
(-3175 1900);
DISPLAY 1.595745 (-3175 1900);
PAINT GREEN (-3175 1900);
DISPLAY INVISIBLE (-3175 1900);
FORCEPROP 1 LAST PATH I110
J 2
(-2848 2025);
DISPLAY 0.872340 (-2848 2025);
PAINT GREEN (-2848 2025);
DISPLAY INVISIBLE (-2848 2025);
FORCEADD TAP..6
R 2
(-2850 2125);
FORCEPROP 3 LASTPIN (-2900 2125) SIG_NAME M_L_MA<4>
J 0
(-2890 2135);
DISPLAY 0.659574 (-2890 2135);
PAINT MONO (-2890 2135);
DISPLAY INVISIBLE (-2890 2135);
FORCEPROP 1 LASTPIN (-2900 2125) BN 4
J 2
(-2848 2133);
DISPLAY 0.617021 (-2848 2133);
PAINT GREEN (-2848 2133);
FORCEPROP 2 LAST CDS_LIB mstr_standard
J 0
(-2850 2125);
PAINT MONO (-2850 2125);
DISPLAY INVISIBLE (-2850 2125);
FORCEPROP 1 LAST BODY_TYPE PLUMBING
J 2
(-2850 2075);
DISPLAY 1.595745 (-2850 2075);
PAINT GREEN (-2850 2075);
DISPLAY INVISIBLE (-2850 2075);
FORCEPROP 1 LAST HDL_TAP TRUE
J 2
(-3175 2000);
DISPLAY 1.595745 (-3175 2000);
PAINT GREEN (-3175 2000);
DISPLAY INVISIBLE (-3175 2000);
FORCEPROP 1 LAST PATH I111
J 2
(-2848 2125);
DISPLAY 0.872340 (-2848 2125);
PAINT GREEN (-2848 2125);
DISPLAY INVISIBLE (-2848 2125);
FORCEADD TAP..6
R 2
(-2850 2175);
FORCEPROP 3 LASTPIN (-2900 2175) SIG_NAME M_L_MA<5>
J 0
(-2890 2185);
DISPLAY 0.659574 (-2890 2185);
PAINT MONO (-2890 2185);
DISPLAY INVISIBLE (-2890 2185);
FORCEPROP 1 LASTPIN (-2900 2175) BN 5
J 2
(-2848 2183);
DISPLAY 0.617021 (-2848 2183);
PAINT GREEN (-2848 2183);
FORCEPROP 2 LAST CDS_LIB mstr_standard
J 0
(-2850 2175);
PAINT MONO (-2850 2175);
DISPLAY INVISIBLE (-2850 2175);
FORCEPROP 1 LAST BODY_TYPE PLUMBING
J 2
(-2850 2125);
DISPLAY 1.595745 (-2850 2125);
PAINT GREEN (-2850 2125);
DISPLAY INVISIBLE (-2850 2125);
FORCEPROP 1 LAST HDL_TAP TRUE
J 2
(-3175 2050);
DISPLAY 1.595745 (-3175 2050);
PAINT GREEN (-3175 2050);
DISPLAY INVISIBLE (-3175 2050);
FORCEPROP 1 LAST PATH I112
J 2
(-2848 2175);
DISPLAY 0.872340 (-2848 2175);
PAINT GREEN (-2848 2175);
DISPLAY INVISIBLE (-2848 2175);
FORCEADD TAP..6
R 2
(-2850 2225);
FORCEPROP 3 LASTPIN (-2900 2225) SIG_NAME M_L_MA<6>
J 0
(-2890 2235);
DISPLAY 0.659574 (-2890 2235);
PAINT MONO (-2890 2235);
DISPLAY INVISIBLE (-2890 2235);
FORCEPROP 1 LASTPIN (-2900 2225) BN 6
J 2
(-2848 2233);
DISPLAY 0.617021 (-2848 2233);
PAINT GREEN (-2848 2233);
FORCEPROP 2 LAST CDS_LIB mstr_standard
J 0
(-2850 2225);
PAINT MONO (-2850 2225);
DISPLAY INVISIBLE (-2850 2225);
FORCEPROP 1 LAST BODY_TYPE PLUMBING
J 2
(-2850 2175);
DISPLAY 1.595745 (-2850 2175);
PAINT GREEN (-2850 2175);
DISPLAY INVISIBLE (-2850 2175);
FORCEPROP 1 LAST HDL_TAP TRUE
J 2
(-3175 2100);
DISPLAY 1.595745 (-3175 2100);
PAINT GREEN (-3175 2100);
DISPLAY INVISIBLE (-3175 2100);
FORCEPROP 1 LAST PATH I113
J 2
(-2848 2225);
DISPLAY 0.872340 (-2848 2225);
PAINT GREEN (-2848 2225);
DISPLAY INVISIBLE (-2848 2225);
FORCEADD TAP..6
R 2
(-2850 2325);
FORCEPROP 3 LASTPIN (-2900 2325) SIG_NAME M_L_MA<8>
J 0
(-2890 2335);
DISPLAY 0.659574 (-2890 2335);
PAINT MONO (-2890 2335);
DISPLAY INVISIBLE (-2890 2335);
FORCEPROP 1 LASTPIN (-2900 2325) BN 8
J 2
(-2848 2333);
DISPLAY 0.617021 (-2848 2333);
PAINT GREEN (-2848 2333);
FORCEPROP 2 LAST CDS_LIB mstr_standard
J 0
(-2850 2325);
PAINT MONO (-2850 2325);
DISPLAY INVISIBLE (-2850 2325);
FORCEPROP 1 LAST BODY_TYPE PLUMBING
J 2
(-2850 2275);
DISPLAY 1.595745 (-2850 2275);
PAINT GREEN (-2850 2275);
DISPLAY INVISIBLE (-2850 2275);
FORCEPROP 1 LAST HDL_TAP TRUE
J 2
(-3175 2200);
DISPLAY 1.595745 (-3175 2200);
PAINT GREEN (-3175 2200);
DISPLAY INVISIBLE (-3175 2200);
FORCEPROP 1 LAST PATH I114
J 2
(-2848 2325);
DISPLAY 0.872340 (-2848 2325);
PAINT GREEN (-2848 2325);
DISPLAY INVISIBLE (-2848 2325);
FORCEADD TAP..6
R 2
(-2850 2275);
FORCEPROP 3 LASTPIN (-2900 2275) SIG_NAME M_L_MA<7>
J 0
(-2890 2285);
DISPLAY 0.659574 (-2890 2285);
PAINT MONO (-2890 2285);
DISPLAY INVISIBLE (-2890 2285);
FORCEPROP 1 LASTPIN (-2900 2275) BN 7
J 2
(-2848 2283);
DISPLAY 0.617021 (-2848 2283);
PAINT GREEN (-2848 2283);
FORCEPROP 2 LAST CDS_LIB mstr_standard
J 0
(-2850 2275);
PAINT MONO (-2850 2275);
DISPLAY INVISIBLE (-2850 2275);
FORCEPROP 1 LAST BODY_TYPE PLUMBING
J 2
(-2850 2225);
DISPLAY 1.595745 (-2850 2225);
PAINT GREEN (-2850 2225);
DISPLAY INVISIBLE (-2850 2225);
FORCEPROP 1 LAST HDL_TAP TRUE
J 2
(-3175 2150);
DISPLAY 1.595745 (-3175 2150);
PAINT GREEN (-3175 2150);
DISPLAY INVISIBLE (-3175 2150);
FORCEPROP 1 LAST PATH I115
J 2
(-2848 2275);
DISPLAY 0.872340 (-2848 2275);
PAINT GREEN (-2848 2275);
DISPLAY INVISIBLE (-2848 2275);
FORCEADD TAP..6
R 2
(-2850 2475);
FORCEPROP 3 LASTPIN (-2900 2475) SIG_NAME M_L_MA<11>
J 0
(-2890 2485);
DISPLAY 0.659574 (-2890 2485);
PAINT MONO (-2890 2485);
DISPLAY INVISIBLE (-2890 2485);
FORCEPROP 1 LASTPIN (-2900 2475) BN 11
J 2
(-2848 2483);
DISPLAY 0.617021 (-2848 2483);
PAINT GREEN (-2848 2483);
FORCEPROP 2 LAST CDS_LIB mstr_standard
J 0
(-2850 2475);
PAINT MONO (-2850 2475);
DISPLAY INVISIBLE (-2850 2475);
FORCEPROP 1 LAST BODY_TYPE PLUMBING
J 2
(-2850 2425);
DISPLAY 1.595745 (-2850 2425);
PAINT GREEN (-2850 2425);
DISPLAY INVISIBLE (-2850 2425);
FORCEPROP 1 LAST HDL_TAP TRUE
J 2
(-3175 2350);
DISPLAY 1.595745 (-3175 2350);
PAINT GREEN (-3175 2350);
DISPLAY INVISIBLE (-3175 2350);
FORCEPROP 1 LAST PATH I116
J 2
(-2848 2475);
DISPLAY 0.872340 (-2848 2475);
PAINT GREEN (-2848 2475);
DISPLAY INVISIBLE (-2848 2475);
FORCEADD TAP..6
R 2
(-2850 2425);
FORCEPROP 3 LASTPIN (-2900 2425) SIG_NAME M_L_MA<10>
J 0
(-2890 2435);
DISPLAY 0.659574 (-2890 2435);
PAINT MONO (-2890 2435);
DISPLAY INVISIBLE (-2890 2435);
FORCEPROP 1 LASTPIN (-2900 2425) BN 10
J 2
(-2848 2433);
DISPLAY 0.617021 (-2848 2433);
PAINT GREEN (-2848 2433);
FORCEPROP 2 LAST CDS_LIB mstr_standard
J 0
(-2850 2425);
PAINT MONO (-2850 2425);
DISPLAY INVISIBLE (-2850 2425);
FORCEPROP 1 LAST BODY_TYPE PLUMBING
J 2
(-2850 2375);
DISPLAY 1.595745 (-2850 2375);
PAINT GREEN (-2850 2375);
DISPLAY INVISIBLE (-2850 2375);
FORCEPROP 1 LAST HDL_TAP TRUE
J 2
(-3175 2300);
DISPLAY 1.595745 (-3175 2300);
PAINT GREEN (-3175 2300);
DISPLAY INVISIBLE (-3175 2300);
FORCEPROP 1 LAST PATH I117
J 2
(-2848 2425);
DISPLAY 0.872340 (-2848 2425);
PAINT GREEN (-2848 2425);
DISPLAY INVISIBLE (-2848 2425);
FORCEADD TAP..6
R 2
(-2850 2375);
FORCEPROP 3 LASTPIN (-2900 2375) SIG_NAME M_L_MA<9>
J 0
(-2890 2385);
DISPLAY 0.659574 (-2890 2385);
PAINT MONO (-2890 2385);
DISPLAY INVISIBLE (-2890 2385);
FORCEPROP 1 LASTPIN (-2900 2375) BN 9
J 2
(-2848 2383);
DISPLAY 0.617021 (-2848 2383);
PAINT GREEN (-2848 2383);
FORCEPROP 2 LAST CDS_LIB mstr_standard
J 0
(-2850 2375);
PAINT MONO (-2850 2375);
DISPLAY INVISIBLE (-2850 2375);
FORCEPROP 1 LAST BODY_TYPE PLUMBING
J 2
(-2850 2325);
DISPLAY 1.595745 (-2850 2325);
PAINT GREEN (-2850 2325);
DISPLAY INVISIBLE (-2850 2325);
FORCEPROP 1 LAST HDL_TAP TRUE
J 2
(-3175 2250);
DISPLAY 1.595745 (-3175 2250);
PAINT GREEN (-3175 2250);
DISPLAY INVISIBLE (-3175 2250);
FORCEPROP 1 LAST PATH I118
J 2
(-2848 2375);
DISPLAY 0.872340 (-2848 2375);
PAINT GREEN (-2848 2375);
DISPLAY INVISIBLE (-2848 2375);
FORCEADD TAP..6
R 2
(-2850 2525);
FORCEPROP 3 LASTPIN (-2900 2525) SIG_NAME M_L_MA<12>
J 0
(-2890 2535);
DISPLAY 0.659574 (-2890 2535);
PAINT MONO (-2890 2535);
DISPLAY INVISIBLE (-2890 2535);
FORCEPROP 1 LASTPIN (-2900 2525) BN 12
J 2
(-2848 2533);
DISPLAY 0.617021 (-2848 2533);
PAINT GREEN (-2848 2533);
FORCEPROP 2 LAST CDS_LIB mstr_standard
J 0
(-2850 2525);
PAINT MONO (-2850 2525);
DISPLAY INVISIBLE (-2850 2525);
FORCEPROP 1 LAST BODY_TYPE PLUMBING
J 2
(-2850 2475);
DISPLAY 1.595745 (-2850 2475);
PAINT GREEN (-2850 2475);
DISPLAY INVISIBLE (-2850 2475);
FORCEPROP 1 LAST HDL_TAP TRUE
J 2
(-3175 2400);
DISPLAY 1.595745 (-3175 2400);
PAINT GREEN (-3175 2400);
DISPLAY INVISIBLE (-3175 2400);
FORCEPROP 1 LAST PATH I119
J 2
(-2848 2525);
DISPLAY 0.872340 (-2848 2525);
PAINT GREEN (-2848 2525);
DISPLAY INVISIBLE (-2848 2525);
FORCEADD TAP..6
(-5575 975);
FORCEPROP 3 LASTPIN (-5525 975) SIG_NAME M_L_CLK_DP<3>
J 0
(-5515 985);
DISPLAY 0.659574 (-5515 985);
PAINT MONO (-5515 985);
DISPLAY INVISIBLE (-5515 985);
FORCEPROP 1 LASTPIN (-5525 975) BN 3
J 0
(-5577 983);
DISPLAY 0.617021 (-5577 983);
PAINT GREEN (-5577 983);
FORCEPROP 2 LAST CDS_LIB mstr_standard
J 0
(-5575 975);
PAINT MONO (-5575 975);
DISPLAY INVISIBLE (-5575 975);
FORCEPROP 1 LAST BODY_TYPE PLUMBING
J 0
(-5575 925);
DISPLAY 1.595745 (-5575 925);
PAINT GREEN (-5575 925);
DISPLAY INVISIBLE (-5575 925);
FORCEPROP 1 LAST HDL_TAP TRUE
J 0
(-5250 850);
DISPLAY 1.595745 (-5250 850);
PAINT GREEN (-5250 850);
DISPLAY INVISIBLE (-5250 850);
FORCEPROP 1 LAST PATH I12
J 0
(-5577 975);
DISPLAY 0.872340 (-5577 975);
PAINT GREEN (-5577 975);
DISPLAY INVISIBLE (-5577 975);
FORCEADD TAP..6
R 2
(-2850 2575);
FORCEPROP 3 LASTPIN (-2900 2575) SIG_NAME M_L_MA<13>
J 0
(-2890 2585);
DISPLAY 0.659574 (-2890 2585);
PAINT MONO (-2890 2585);
DISPLAY INVISIBLE (-2890 2585);
FORCEPROP 1 LASTPIN (-2900 2575) BN 13
J 2
(-2848 2583);
DISPLAY 0.617021 (-2848 2583);
PAINT GREEN (-2848 2583);
FORCEPROP 2 LAST CDS_LIB mstr_standard
J 0
(-2850 2575);
PAINT MONO (-2850 2575);
DISPLAY INVISIBLE (-2850 2575);
FORCEPROP 1 LAST BODY_TYPE PLUMBING
J 2
(-2850 2525);
DISPLAY 1.595745 (-2850 2525);
PAINT GREEN (-2850 2525);
DISPLAY INVISIBLE (-2850 2525);
FORCEPROP 1 LAST HDL_TAP TRUE
J 2
(-3175 2450);
DISPLAY 1.595745 (-3175 2450);
PAINT GREEN (-3175 2450);
DISPLAY INVISIBLE (-3175 2450);
FORCEPROP 1 LAST PATH I120
J 2
(-2848 2575);
DISPLAY 0.872340 (-2848 2575);
PAINT GREEN (-2848 2575);
DISPLAY INVISIBLE (-2848 2575);
FORCEADD TAP..6
R 2
(-2850 2625);
FORCEPROP 3 LASTPIN (-2900 2625) SIG_NAME M_L_MA<14>
J 0
(-2890 2635);
DISPLAY 0.659574 (-2890 2635);
PAINT MONO (-2890 2635);
DISPLAY INVISIBLE (-2890 2635);
FORCEPROP 1 LASTPIN (-2900 2625) BN 14
J 2
(-2848 2633);
DISPLAY 0.617021 (-2848 2633);
PAINT GREEN (-2848 2633);
FORCEPROP 2 LAST CDS_LIB mstr_standard
J 0
(-2850 2625);
PAINT MONO (-2850 2625);
DISPLAY INVISIBLE (-2850 2625);
FORCEPROP 1 LAST BODY_TYPE PLUMBING
J 2
(-2850 2575);
DISPLAY 1.595745 (-2850 2575);
PAINT GREEN (-2850 2575);
DISPLAY INVISIBLE (-2850 2575);
FORCEPROP 1 LAST HDL_TAP TRUE
J 2
(-3175 2500);
DISPLAY 1.595745 (-3175 2500);
PAINT GREEN (-3175 2500);
DISPLAY INVISIBLE (-3175 2500);
FORCEPROP 1 LAST PATH I121
J 2
(-2848 2625);
DISPLAY 0.872340 (-2848 2625);
PAINT GREEN (-2848 2625);
DISPLAY INVISIBLE (-2848 2625);
FORCEADD TAP..6
R 2
(-2850 2675);
FORCEPROP 3 LASTPIN (-2900 2675) SIG_NAME M_L_MA<15>
J 0
(-2890 2685);
DISPLAY 0.659574 (-2890 2685);
PAINT MONO (-2890 2685);
DISPLAY INVISIBLE (-2890 2685);
FORCEPROP 1 LASTPIN (-2900 2675) BN 15
J 2
(-2848 2683);
DISPLAY 0.617021 (-2848 2683);
PAINT GREEN (-2848 2683);
FORCEPROP 2 LAST CDS_LIB mstr_standard
J 0
(-2850 2675);
PAINT MONO (-2850 2675);
DISPLAY INVISIBLE (-2850 2675);
FORCEPROP 1 LAST BODY_TYPE PLUMBING
J 2
(-2850 2625);
DISPLAY 1.595745 (-2850 2625);
PAINT GREEN (-2850 2625);
DISPLAY INVISIBLE (-2850 2625);
FORCEPROP 1 LAST HDL_TAP TRUE
J 2
(-3175 2550);
DISPLAY 1.595745 (-3175 2550);
PAINT GREEN (-3175 2550);
DISPLAY INVISIBLE (-3175 2550);
FORCEPROP 1 LAST PATH I122
J 2
(-2848 2675);
DISPLAY 0.872340 (-2848 2675);
PAINT GREEN (-2848 2675);
DISPLAY INVISIBLE (-2848 2675);
FORCEADD TAP..6
R 2
(-2850 2725);
FORCEPROP 3 LASTPIN (-2900 2725) SIG_NAME M_L_MA<16>
J 0
(-2890 2735);
DISPLAY 0.659574 (-2890 2735);
PAINT MONO (-2890 2735);
DISPLAY INVISIBLE (-2890 2735);
FORCEPROP 1 LASTPIN (-2900 2725) BN 16
J 2
(-2848 2733);
DISPLAY 0.617021 (-2848 2733);
PAINT GREEN (-2848 2733);
FORCEPROP 2 LAST CDS_LIB mstr_standard
J 0
(-2850 2725);
PAINT MONO (-2850 2725);
DISPLAY INVISIBLE (-2850 2725);
FORCEPROP 1 LAST BODY_TYPE PLUMBING
J 2
(-2850 2675);
DISPLAY 1.595745 (-2850 2675);
PAINT GREEN (-2850 2675);
DISPLAY INVISIBLE (-2850 2675);
FORCEPROP 1 LAST HDL_TAP TRUE
J 2
(-3175 2600);
DISPLAY 1.595745 (-3175 2600);
PAINT GREEN (-3175 2600);
DISPLAY INVISIBLE (-3175 2600);
FORCEPROP 1 LAST PATH I123
J 2
(-2848 2725);
DISPLAY 0.872340 (-2848 2725);
PAINT GREEN (-2848 2725);
DISPLAY INVISIBLE (-2848 2725);
FORCEADD TAP..6
R 2
(-2850 2775);
FORCEPROP 3 LASTPIN (-2900 2775) SIG_NAME M_L_MA<17>
J 0
(-2890 2785);
DISPLAY 0.659574 (-2890 2785);
PAINT MONO (-2890 2785);
DISPLAY INVISIBLE (-2890 2785);
FORCEPROP 1 LASTPIN (-2900 2775) BN 17
J 2
(-2848 2783);
DISPLAY 0.617021 (-2848 2783);
PAINT GREEN (-2848 2783);
FORCEPROP 2 LAST CDS_LIB mstr_standard
J 0
(-2850 2775);
PAINT MONO (-2850 2775);
DISPLAY INVISIBLE (-2850 2775);
FORCEPROP 1 LAST BODY_TYPE PLUMBING
J 2
(-2850 2725);
DISPLAY 1.595745 (-2850 2725);
PAINT GREEN (-2850 2725);
DISPLAY INVISIBLE (-2850 2725);
FORCEPROP 1 LAST HDL_TAP TRUE
J 2
(-3175 2650);
DISPLAY 1.595745 (-3175 2650);
PAINT GREEN (-3175 2650);
DISPLAY INVISIBLE (-3175 2650);
FORCEPROP 1 LAST PATH I124
J 2
(-2848 2775);
DISPLAY 0.872340 (-2848 2775);
PAINT GREEN (-2848 2775);
DISPLAY INVISIBLE (-2848 2775);
FORCEADD TAP..6
R 2
(-2850 2925);
FORCEPROP 3 LASTPIN (-2900 2925) SIG_NAME M_L_DQS_DN<1>
J 0
(-2890 2935);
DISPLAY 0.659574 (-2890 2935);
PAINT MONO (-2890 2935);
DISPLAY INVISIBLE (-2890 2935);
FORCEPROP 1 LASTPIN (-2900 2925) BN 1
J 2
(-2848 2933);
DISPLAY 0.617021 (-2848 2933);
PAINT GREEN (-2848 2933);
FORCEPROP 2 LAST CDS_LIB mstr_standard
J 0
(-2850 2925);
PAINT MONO (-2850 2925);
DISPLAY INVISIBLE (-2850 2925);
FORCEPROP 1 LAST BODY_TYPE PLUMBING
J 2
(-2850 2875);
DISPLAY 1.595745 (-2850 2875);
PAINT GREEN (-2850 2875);
DISPLAY INVISIBLE (-2850 2875);
FORCEPROP 1 LAST HDL_TAP TRUE
J 2
(-3175 2800);
DISPLAY 1.595745 (-3175 2800);
PAINT GREEN (-3175 2800);
DISPLAY INVISIBLE (-3175 2800);
FORCEPROP 1 LAST PATH I125
J 2
(-2848 2925);
DISPLAY 0.872340 (-2848 2925);
PAINT GREEN (-2848 2925);
DISPLAY INVISIBLE (-2848 2925);
FORCEADD TAP..6
R 2
(-2850 2975);
FORCEPROP 3 LASTPIN (-2900 2975) SIG_NAME M_L_DQS_DN<2>
J 0
(-2890 2985);
DISPLAY 0.659574 (-2890 2985);
PAINT MONO (-2890 2985);
DISPLAY INVISIBLE (-2890 2985);
FORCEPROP 1 LASTPIN (-2900 2975) BN 2
J 2
(-2848 2983);
DISPLAY 0.617021 (-2848 2983);
PAINT GREEN (-2848 2983);
FORCEPROP 2 LAST CDS_LIB mstr_standard
J 0
(-2850 2975);
PAINT MONO (-2850 2975);
DISPLAY INVISIBLE (-2850 2975);
FORCEPROP 1 LAST BODY_TYPE PLUMBING
J 2
(-2850 2925);
DISPLAY 1.595745 (-2850 2925);
PAINT GREEN (-2850 2925);
DISPLAY INVISIBLE (-2850 2925);
FORCEPROP 1 LAST HDL_TAP TRUE
J 2
(-3175 2850);
DISPLAY 1.595745 (-3175 2850);
PAINT GREEN (-3175 2850);
DISPLAY INVISIBLE (-3175 2850);
FORCEPROP 1 LAST PATH I126
J 2
(-2848 2975);
DISPLAY 0.872340 (-2848 2975);
PAINT GREEN (-2848 2975);
DISPLAY INVISIBLE (-2848 2975);
FORCEADD TAP..6
R 2
(-2850 2875);
FORCEPROP 3 LASTPIN (-2900 2875) SIG_NAME M_L_DQS_DN<0>
J 0
(-2890 2885);
DISPLAY 0.659574 (-2890 2885);
PAINT MONO (-2890 2885);
DISPLAY INVISIBLE (-2890 2885);
FORCEPROP 1 LASTPIN (-2900 2875) BN 0
J 2
(-2848 2883);
DISPLAY 0.617021 (-2848 2883);
PAINT GREEN (-2848 2883);
FORCEPROP 2 LAST CDS_LIB mstr_standard
J 0
(-2850 2875);
PAINT MONO (-2850 2875);
DISPLAY INVISIBLE (-2850 2875);
FORCEPROP 1 LAST BODY_TYPE PLUMBING
J 2
(-2850 2825);
DISPLAY 1.595745 (-2850 2825);
PAINT GREEN (-2850 2825);
DISPLAY INVISIBLE (-2850 2825);
FORCEPROP 1 LAST HDL_TAP TRUE
J 2
(-3175 2750);
DISPLAY 1.595745 (-3175 2750);
PAINT GREEN (-3175 2750);
DISPLAY INVISIBLE (-3175 2750);
FORCEPROP 1 LAST PATH I127
J 2
(-2848 2875);
DISPLAY 0.872340 (-2848 2875);
PAINT GREEN (-2848 2875);
DISPLAY INVISIBLE (-2848 2875);
FORCEADD TAP..6
R 2
(-2850 3075);
FORCEPROP 3 LASTPIN (-2900 3075) SIG_NAME M_L_DQS_DN<4>
J 0
(-2890 3085);
DISPLAY 0.659574 (-2890 3085);
PAINT MONO (-2890 3085);
DISPLAY INVISIBLE (-2890 3085);
FORCEPROP 1 LASTPIN (-2900 3075) BN 4
J 2
(-2848 3083);
DISPLAY 0.617021 (-2848 3083);
PAINT GREEN (-2848 3083);
FORCEPROP 2 LAST CDS_LIB mstr_standard
J 0
(-2850 3075);
PAINT MONO (-2850 3075);
DISPLAY INVISIBLE (-2850 3075);
FORCEPROP 1 LAST BODY_TYPE PLUMBING
J 2
(-2850 3025);
DISPLAY 1.595745 (-2850 3025);
PAINT GREEN (-2850 3025);
DISPLAY INVISIBLE (-2850 3025);
FORCEPROP 1 LAST HDL_TAP TRUE
J 2
(-3175 2950);
DISPLAY 1.595745 (-3175 2950);
PAINT GREEN (-3175 2950);
DISPLAY INVISIBLE (-3175 2950);
FORCEPROP 1 LAST PATH I128
J 2
(-2848 3075);
DISPLAY 0.872340 (-2848 3075);
PAINT GREEN (-2848 3075);
DISPLAY INVISIBLE (-2848 3075);
FORCEADD TAP..6
R 2
(-2850 3025);
FORCEPROP 3 LASTPIN (-2900 3025) SIG_NAME M_L_DQS_DN<3>
J 0
(-2890 3035);
DISPLAY 0.659574 (-2890 3035);
PAINT MONO (-2890 3035);
DISPLAY INVISIBLE (-2890 3035);
FORCEPROP 1 LASTPIN (-2900 3025) BN 3
J 2
(-2848 3033);
DISPLAY 0.617021 (-2848 3033);
PAINT GREEN (-2848 3033);
FORCEPROP 2 LAST CDS_LIB mstr_standard
J 0
(-2850 3025);
PAINT MONO (-2850 3025);
DISPLAY INVISIBLE (-2850 3025);
FORCEPROP 1 LAST BODY_TYPE PLUMBING
J 2
(-2850 2975);
DISPLAY 1.595745 (-2850 2975);
PAINT GREEN (-2850 2975);
DISPLAY INVISIBLE (-2850 2975);
FORCEPROP 1 LAST HDL_TAP TRUE
J 2
(-3175 2900);
DISPLAY 1.595745 (-3175 2900);
PAINT GREEN (-3175 2900);
DISPLAY INVISIBLE (-3175 2900);
FORCEPROP 1 LAST PATH I129
J 2
(-2848 3025);
DISPLAY 0.872340 (-2848 3025);
PAINT GREEN (-2848 3025);
DISPLAY INVISIBLE (-2848 3025);
FORCEADD TAP..6
(-5575 1075);
FORCEPROP 3 LASTPIN (-5525 1075) SIG_NAME M_L_ECC<0>
J 0
(-5515 1085);
DISPLAY 0.659574 (-5515 1085);
PAINT MONO (-5515 1085);
DISPLAY INVISIBLE (-5515 1085);
FORCEPROP 1 LASTPIN (-5525 1075) BN 0
J 0
(-5577 1083);
DISPLAY 0.617021 (-5577 1083);
PAINT GREEN (-5577 1083);
FORCEPROP 2 LAST CDS_LIB mstr_standard
J 0
(-5575 1075);
PAINT MONO (-5575 1075);
DISPLAY INVISIBLE (-5575 1075);
FORCEPROP 1 LAST BODY_TYPE PLUMBING
J 0
(-5575 1025);
DISPLAY 1.595745 (-5575 1025);
PAINT GREEN (-5575 1025);
DISPLAY INVISIBLE (-5575 1025);
FORCEPROP 1 LAST HDL_TAP TRUE
J 0
(-5250 950);
DISPLAY 1.595745 (-5250 950);
PAINT GREEN (-5250 950);
DISPLAY INVISIBLE (-5250 950);
FORCEPROP 1 LAST PATH I13
J 0
(-5577 1075);
DISPLAY 0.872340 (-5577 1075);
PAINT GREEN (-5577 1075);
DISPLAY INVISIBLE (-5577 1075);
FORCEADD TAP..6
R 2
(-2850 3125);
FORCEPROP 3 LASTPIN (-2900 3125) SIG_NAME M_L_DQS_DN<5>
J 0
(-2890 3135);
DISPLAY 0.659574 (-2890 3135);
PAINT MONO (-2890 3135);
DISPLAY INVISIBLE (-2890 3135);
FORCEPROP 1 LASTPIN (-2900 3125) BN 5
J 2
(-2848 3133);
DISPLAY 0.617021 (-2848 3133);
PAINT GREEN (-2848 3133);
FORCEPROP 2 LAST CDS_LIB mstr_standard
J 0
(-2850 3125);
PAINT MONO (-2850 3125);
DISPLAY INVISIBLE (-2850 3125);
FORCEPROP 1 LAST BODY_TYPE PLUMBING
J 2
(-2850 3075);
DISPLAY 1.595745 (-2850 3075);
PAINT GREEN (-2850 3075);
DISPLAY INVISIBLE (-2850 3075);
FORCEPROP 1 LAST HDL_TAP TRUE
J 2
(-3175 3000);
DISPLAY 1.595745 (-3175 3000);
PAINT GREEN (-3175 3000);
DISPLAY INVISIBLE (-3175 3000);
FORCEPROP 1 LAST PATH I130
J 2
(-2848 3125);
DISPLAY 0.872340 (-2848 3125);
PAINT GREEN (-2848 3125);
DISPLAY INVISIBLE (-2848 3125);
FORCEADD TAP..6
R 2
(-2850 3175);
FORCEPROP 3 LASTPIN (-2900 3175) SIG_NAME M_L_DQS_DN<6>
J 0
(-2890 3185);
DISPLAY 0.659574 (-2890 3185);
PAINT MONO (-2890 3185);
DISPLAY INVISIBLE (-2890 3185);
FORCEPROP 1 LASTPIN (-2900 3175) BN 6
J 2
(-2848 3183);
DISPLAY 0.617021 (-2848 3183);
PAINT GREEN (-2848 3183);
FORCEPROP 2 LAST CDS_LIB mstr_standard
J 0
(-2850 3175);
PAINT MONO (-2850 3175);
DISPLAY INVISIBLE (-2850 3175);
FORCEPROP 1 LAST BODY_TYPE PLUMBING
J 2
(-2850 3125);
DISPLAY 1.595745 (-2850 3125);
PAINT GREEN (-2850 3125);
DISPLAY INVISIBLE (-2850 3125);
FORCEPROP 1 LAST HDL_TAP TRUE
J 2
(-3175 3050);
DISPLAY 1.595745 (-3175 3050);
PAINT GREEN (-3175 3050);
DISPLAY INVISIBLE (-3175 3050);
FORCEPROP 1 LAST PATH I131
J 2
(-2848 3175);
DISPLAY 0.872340 (-2848 3175);
PAINT GREEN (-2848 3175);
DISPLAY INVISIBLE (-2848 3175);
FORCEADD TAP..6
R 2
(-2850 3225);
FORCEPROP 3 LASTPIN (-2900 3225) SIG_NAME M_L_DQS_DN<7>
J 0
(-2890 3235);
DISPLAY 0.659574 (-2890 3235);
PAINT MONO (-2890 3235);
DISPLAY INVISIBLE (-2890 3235);
FORCEPROP 1 LASTPIN (-2900 3225) BN 7
J 2
(-2848 3233);
DISPLAY 0.617021 (-2848 3233);
PAINT GREEN (-2848 3233);
FORCEPROP 2 LAST CDS_LIB mstr_standard
J 0
(-2850 3225);
PAINT MONO (-2850 3225);
DISPLAY INVISIBLE (-2850 3225);
FORCEPROP 1 LAST BODY_TYPE PLUMBING
J 2
(-2850 3175);
DISPLAY 1.595745 (-2850 3175);
PAINT GREEN (-2850 3175);
DISPLAY INVISIBLE (-2850 3175);
FORCEPROP 1 LAST HDL_TAP TRUE
J 2
(-3175 3100);
DISPLAY 1.595745 (-3175 3100);
PAINT GREEN (-3175 3100);
DISPLAY INVISIBLE (-3175 3100);
FORCEPROP 1 LAST PATH I132
J 2
(-2848 3225);
DISPLAY 0.872340 (-2848 3225);
PAINT GREEN (-2848 3225);
DISPLAY INVISIBLE (-2848 3225);
FORCEADD TAP..6
R 2
(-2850 3275);
FORCEPROP 3 LASTPIN (-2900 3275) SIG_NAME M_L_DQS_DN<8>
J 0
(-2890 3285);
DISPLAY 0.659574 (-2890 3285);
PAINT MONO (-2890 3285);
DISPLAY INVISIBLE (-2890 3285);
FORCEPROP 1 LASTPIN (-2900 3275) BN 8
J 2
(-2848 3283);
DISPLAY 0.617021 (-2848 3283);
PAINT GREEN (-2848 3283);
FORCEPROP 2 LAST CDS_LIB mstr_standard
J 0
(-2850 3275);
PAINT MONO (-2850 3275);
DISPLAY INVISIBLE (-2850 3275);
FORCEPROP 1 LAST BODY_TYPE PLUMBING
J 2
(-2850 3225);
DISPLAY 1.595745 (-2850 3225);
PAINT GREEN (-2850 3225);
DISPLAY INVISIBLE (-2850 3225);
FORCEPROP 1 LAST HDL_TAP TRUE
J 2
(-3175 3150);
DISPLAY 1.595745 (-3175 3150);
PAINT GREEN (-3175 3150);
DISPLAY INVISIBLE (-3175 3150);
FORCEPROP 1 LAST PATH I133
J 2
(-2848 3275);
DISPLAY 0.872340 (-2848 3275);
PAINT GREEN (-2848 3275);
DISPLAY INVISIBLE (-2848 3275);
FORCEADD TAP..6
R 2
(-2850 3325);
FORCEPROP 3 LASTPIN (-2900 3325) SIG_NAME M_L_DQS_DN<9>
J 0
(-2890 3335);
DISPLAY 0.659574 (-2890 3335);
PAINT MONO (-2890 3335);
DISPLAY INVISIBLE (-2890 3335);
FORCEPROP 1 LASTPIN (-2900 3325) BN 9
J 2
(-2848 3333);
DISPLAY 0.617021 (-2848 3333);
PAINT GREEN (-2848 3333);
FORCEPROP 2 LAST CDS_LIB mstr_standard
J 0
(-2850 3325);
PAINT MONO (-2850 3325);
DISPLAY INVISIBLE (-2850 3325);
FORCEPROP 1 LAST BODY_TYPE PLUMBING
J 2
(-2850 3275);
DISPLAY 1.595745 (-2850 3275);
PAINT GREEN (-2850 3275);
DISPLAY INVISIBLE (-2850 3275);
FORCEPROP 1 LAST HDL_TAP TRUE
J 2
(-3175 3200);
DISPLAY 1.595745 (-3175 3200);
PAINT GREEN (-3175 3200);
DISPLAY INVISIBLE (-3175 3200);
FORCEPROP 1 LAST PATH I134
J 2
(-2848 3325);
DISPLAY 0.872340 (-2848 3325);
PAINT GREEN (-2848 3325);
DISPLAY INVISIBLE (-2848 3325);
FORCEADD TAP..6
R 2
(-2850 3375);
FORCEPROP 3 LASTPIN (-2900 3375) SIG_NAME M_L_DQS_DN<10>
J 0
(-2890 3385);
DISPLAY 0.659574 (-2890 3385);
PAINT MONO (-2890 3385);
DISPLAY INVISIBLE (-2890 3385);
FORCEPROP 1 LASTPIN (-2900 3375) BN 10
J 2
(-2848 3383);
DISPLAY 0.617021 (-2848 3383);
PAINT GREEN (-2848 3383);
FORCEPROP 2 LAST CDS_LIB mstr_standard
J 0
(-2850 3375);
PAINT MONO (-2850 3375);
DISPLAY INVISIBLE (-2850 3375);
FORCEPROP 1 LAST BODY_TYPE PLUMBING
J 2
(-2850 3325);
DISPLAY 1.595745 (-2850 3325);
PAINT GREEN (-2850 3325);
DISPLAY INVISIBLE (-2850 3325);
FORCEPROP 1 LAST HDL_TAP TRUE
J 2
(-3175 3250);
DISPLAY 1.595745 (-3175 3250);
PAINT GREEN (-3175 3250);
DISPLAY INVISIBLE (-3175 3250);
FORCEPROP 1 LAST PATH I135
J 2
(-2848 3375);
DISPLAY 0.872340 (-2848 3375);
PAINT GREEN (-2848 3375);
DISPLAY INVISIBLE (-2848 3375);
FORCEADD TAP..6
R 2
(-2850 3475);
FORCEPROP 3 LASTPIN (-2900 3475) SIG_NAME M_L_DQS_DN<12>
J 0
(-2890 3485);
DISPLAY 0.659574 (-2890 3485);
PAINT MONO (-2890 3485);
DISPLAY INVISIBLE (-2890 3485);
FORCEPROP 1 LASTPIN (-2900 3475) BN 12
J 2
(-2848 3483);
DISPLAY 0.617021 (-2848 3483);
PAINT GREEN (-2848 3483);
FORCEPROP 2 LAST CDS_LIB mstr_standard
J 0
(-2850 3475);
PAINT MONO (-2850 3475);
DISPLAY INVISIBLE (-2850 3475);
FORCEPROP 1 LAST BODY_TYPE PLUMBING
J 2
(-2850 3425);
DISPLAY 1.595745 (-2850 3425);
PAINT GREEN (-2850 3425);
DISPLAY INVISIBLE (-2850 3425);
FORCEPROP 1 LAST HDL_TAP TRUE
J 2
(-3175 3350);
DISPLAY 1.595745 (-3175 3350);
PAINT GREEN (-3175 3350);
DISPLAY INVISIBLE (-3175 3350);
FORCEPROP 1 LAST PATH I136
J 2
(-2848 3475);
DISPLAY 0.872340 (-2848 3475);
PAINT GREEN (-2848 3475);
DISPLAY INVISIBLE (-2848 3475);
FORCEADD TAP..6
R 2
(-2850 3425);
FORCEPROP 3 LASTPIN (-2900 3425) SIG_NAME M_L_DQS_DN<11>
J 0
(-2890 3435);
DISPLAY 0.659574 (-2890 3435);
PAINT MONO (-2890 3435);
DISPLAY INVISIBLE (-2890 3435);
FORCEPROP 1 LASTPIN (-2900 3425) BN 11
J 2
(-2848 3433);
DISPLAY 0.617021 (-2848 3433);
PAINT GREEN (-2848 3433);
FORCEPROP 2 LAST CDS_LIB mstr_standard
J 0
(-2850 3425);
PAINT MONO (-2850 3425);
DISPLAY INVISIBLE (-2850 3425);
FORCEPROP 1 LAST BODY_TYPE PLUMBING
J 2
(-2850 3375);
DISPLAY 1.595745 (-2850 3375);
PAINT GREEN (-2850 3375);
DISPLAY INVISIBLE (-2850 3375);
FORCEPROP 1 LAST HDL_TAP TRUE
J 2
(-3175 3300);
DISPLAY 1.595745 (-3175 3300);
PAINT GREEN (-3175 3300);
DISPLAY INVISIBLE (-3175 3300);
FORCEPROP 1 LAST PATH I137
J 2
(-2848 3425);
DISPLAY 0.872340 (-2848 3425);
PAINT GREEN (-2848 3425);
DISPLAY INVISIBLE (-2848 3425);
FORCEADD TAP..6
R 2
(-2850 3625);
FORCEPROP 3 LASTPIN (-2900 3625) SIG_NAME M_L_DQS_DN<15>
J 0
(-2890 3635);
DISPLAY 0.659574 (-2890 3635);
PAINT MONO (-2890 3635);
DISPLAY INVISIBLE (-2890 3635);
FORCEPROP 1 LASTPIN (-2900 3625) BN 15
J 2
(-2848 3633);
DISPLAY 0.617021 (-2848 3633);
PAINT GREEN (-2848 3633);
FORCEPROP 2 LAST CDS_LIB mstr_standard
J 0
(-2850 3625);
PAINT MONO (-2850 3625);
DISPLAY INVISIBLE (-2850 3625);
FORCEPROP 1 LAST BODY_TYPE PLUMBING
J 2
(-2850 3575);
DISPLAY 1.595745 (-2850 3575);
PAINT GREEN (-2850 3575);
DISPLAY INVISIBLE (-2850 3575);
FORCEPROP 1 LAST HDL_TAP TRUE
J 2
(-3175 3500);
DISPLAY 1.595745 (-3175 3500);
PAINT GREEN (-3175 3500);
DISPLAY INVISIBLE (-3175 3500);
FORCEPROP 1 LAST PATH I138
J 2
(-2848 3625);
DISPLAY 0.872340 (-2848 3625);
PAINT GREEN (-2848 3625);
DISPLAY INVISIBLE (-2848 3625);
FORCEADD TAP..6
R 2
(-2850 3575);
FORCEPROP 3 LASTPIN (-2900 3575) SIG_NAME M_L_DQS_DN<14>
J 0
(-2890 3585);
DISPLAY 0.659574 (-2890 3585);
PAINT MONO (-2890 3585);
DISPLAY INVISIBLE (-2890 3585);
FORCEPROP 1 LASTPIN (-2900 3575) BN 14
J 2
(-2848 3583);
DISPLAY 0.617021 (-2848 3583);
PAINT GREEN (-2848 3583);
FORCEPROP 2 LAST CDS_LIB mstr_standard
J 0
(-2850 3575);
PAINT MONO (-2850 3575);
DISPLAY INVISIBLE (-2850 3575);
FORCEPROP 1 LAST BODY_TYPE PLUMBING
J 2
(-2850 3525);
DISPLAY 1.595745 (-2850 3525);
PAINT GREEN (-2850 3525);
DISPLAY INVISIBLE (-2850 3525);
FORCEPROP 1 LAST HDL_TAP TRUE
J 2
(-3175 3450);
DISPLAY 1.595745 (-3175 3450);
PAINT GREEN (-3175 3450);
DISPLAY INVISIBLE (-3175 3450);
FORCEPROP 1 LAST PATH I139
J 2
(-2848 3575);
DISPLAY 0.872340 (-2848 3575);
PAINT GREEN (-2848 3575);
DISPLAY INVISIBLE (-2848 3575);
FORCEADD TAP..6
(-5575 1125);
FORCEPROP 3 LASTPIN (-5525 1125) SIG_NAME M_L_ECC<1>
J 0
(-5515 1135);
DISPLAY 0.659574 (-5515 1135);
PAINT MONO (-5515 1135);
DISPLAY INVISIBLE (-5515 1135);
FORCEPROP 1 LASTPIN (-5525 1125) BN 1
J 0
(-5577 1133);
DISPLAY 0.617021 (-5577 1133);
PAINT GREEN (-5577 1133);
FORCEPROP 2 LAST CDS_LIB mstr_standard
J 0
(-5575 1125);
PAINT MONO (-5575 1125);
DISPLAY INVISIBLE (-5575 1125);
FORCEPROP 1 LAST BODY_TYPE PLUMBING
J 0
(-5575 1075);
DISPLAY 1.595745 (-5575 1075);
PAINT GREEN (-5575 1075);
DISPLAY INVISIBLE (-5575 1075);
FORCEPROP 1 LAST HDL_TAP TRUE
J 0
(-5250 1000);
DISPLAY 1.595745 (-5250 1000);
PAINT GREEN (-5250 1000);
DISPLAY INVISIBLE (-5250 1000);
FORCEPROP 1 LAST PATH I14
J 0
(-5577 1125);
DISPLAY 0.872340 (-5577 1125);
PAINT GREEN (-5577 1125);
DISPLAY INVISIBLE (-5577 1125);
FORCEADD TAP..6
R 2
(-2850 3525);
FORCEPROP 3 LASTPIN (-2900 3525) SIG_NAME M_L_DQS_DN<13>
J 0
(-2890 3535);
DISPLAY 0.659574 (-2890 3535);
PAINT MONO (-2890 3535);
DISPLAY INVISIBLE (-2890 3535);
FORCEPROP 1 LASTPIN (-2900 3525) BN 13
J 2
(-2848 3533);
DISPLAY 0.617021 (-2848 3533);
PAINT GREEN (-2848 3533);
FORCEPROP 2 LAST CDS_LIB mstr_standard
J 0
(-2850 3525);
PAINT MONO (-2850 3525);
DISPLAY INVISIBLE (-2850 3525);
FORCEPROP 1 LAST BODY_TYPE PLUMBING
J 2
(-2850 3475);
DISPLAY 1.595745 (-2850 3475);
PAINT GREEN (-2850 3475);
DISPLAY INVISIBLE (-2850 3475);
FORCEPROP 1 LAST HDL_TAP TRUE
J 2
(-3175 3400);
DISPLAY 1.595745 (-3175 3400);
PAINT GREEN (-3175 3400);
DISPLAY INVISIBLE (-3175 3400);
FORCEPROP 1 LAST PATH I140
J 2
(-2848 3525);
DISPLAY 0.872340 (-2848 3525);
PAINT GREEN (-2848 3525);
DISPLAY INVISIBLE (-2848 3525);
FORCEADD TAP..6
R 2
(-2850 3675);
FORCEPROP 3 LASTPIN (-2900 3675) SIG_NAME M_L_DQS_DN<16>
J 0
(-2890 3685);
DISPLAY 0.659574 (-2890 3685);
PAINT MONO (-2890 3685);
DISPLAY INVISIBLE (-2890 3685);
FORCEPROP 1 LASTPIN (-2900 3675) BN 16
J 2
(-2848 3683);
DISPLAY 0.617021 (-2848 3683);
PAINT GREEN (-2848 3683);
FORCEPROP 2 LAST CDS_LIB mstr_standard
J 0
(-2850 3675);
PAINT MONO (-2850 3675);
DISPLAY INVISIBLE (-2850 3675);
FORCEPROP 1 LAST BODY_TYPE PLUMBING
J 2
(-2850 3625);
DISPLAY 1.595745 (-2850 3625);
PAINT GREEN (-2850 3625);
DISPLAY INVISIBLE (-2850 3625);
FORCEPROP 1 LAST HDL_TAP TRUE
J 2
(-3175 3550);
DISPLAY 1.595745 (-3175 3550);
PAINT GREEN (-3175 3550);
DISPLAY INVISIBLE (-3175 3550);
FORCEPROP 1 LAST PATH I141
J 2
(-2848 3675);
DISPLAY 0.872340 (-2848 3675);
PAINT GREEN (-2848 3675);
DISPLAY INVISIBLE (-2848 3675);
FORCEADD TAP..6
R 2
(-2850 3725);
FORCEPROP 3 LASTPIN (-2900 3725) SIG_NAME M_L_DQS_DN<17>
J 0
(-2890 3735);
DISPLAY 0.659574 (-2890 3735);
PAINT MONO (-2890 3735);
DISPLAY INVISIBLE (-2890 3735);
FORCEPROP 1 LASTPIN (-2900 3725) BN 17
J 2
(-2848 3733);
DISPLAY 0.617021 (-2848 3733);
PAINT GREEN (-2848 3733);
FORCEPROP 2 LAST CDS_LIB mstr_standard
J 0
(-2850 3725);
PAINT MONO (-2850 3725);
DISPLAY INVISIBLE (-2850 3725);
FORCEPROP 1 LAST BODY_TYPE PLUMBING
J 2
(-2850 3675);
DISPLAY 1.595745 (-2850 3675);
PAINT GREEN (-2850 3675);
DISPLAY INVISIBLE (-2850 3675);
FORCEPROP 1 LAST HDL_TAP TRUE
J 2
(-3175 3600);
DISPLAY 1.595745 (-3175 3600);
PAINT GREEN (-3175 3600);
DISPLAY INVISIBLE (-3175 3600);
FORCEPROP 1 LAST PATH I142
J 2
(-2848 3725);
DISPLAY 0.872340 (-2848 3725);
PAINT GREEN (-2848 3725);
DISPLAY INVISIBLE (-2848 3725);
FORCEADD TAP..6
R 2
(-2850 3825);
FORCEPROP 3 LASTPIN (-2900 3825) SIG_NAME M_L_DQS_DP<0>
J 0
(-2890 3835);
DISPLAY 0.659574 (-2890 3835);
PAINT MONO (-2890 3835);
DISPLAY INVISIBLE (-2890 3835);
FORCEPROP 1 LASTPIN (-2900 3825) BN 0
J 2
(-2848 3833);
DISPLAY 0.617021 (-2848 3833);
PAINT GREEN (-2848 3833);
FORCEPROP 2 LAST CDS_LIB mstr_standard
J 0
(-2850 3825);
PAINT MONO (-2850 3825);
DISPLAY INVISIBLE (-2850 3825);
FORCEPROP 1 LAST BODY_TYPE PLUMBING
J 2
(-2850 3775);
DISPLAY 1.595745 (-2850 3775);
PAINT GREEN (-2850 3775);
DISPLAY INVISIBLE (-2850 3775);
FORCEPROP 1 LAST HDL_TAP TRUE
J 2
(-3175 3700);
DISPLAY 1.595745 (-3175 3700);
PAINT GREEN (-3175 3700);
DISPLAY INVISIBLE (-3175 3700);
FORCEPROP 1 LAST PATH I143
J 2
(-2848 3825);
DISPLAY 0.872340 (-2848 3825);
PAINT GREEN (-2848 3825);
DISPLAY INVISIBLE (-2848 3825);
FORCEADD TAP..6
R 2
(-2850 3875);
FORCEPROP 3 LASTPIN (-2900 3875) SIG_NAME M_L_DQS_DP<1>
J 0
(-2890 3885);
DISPLAY 0.659574 (-2890 3885);
PAINT MONO (-2890 3885);
DISPLAY INVISIBLE (-2890 3885);
FORCEPROP 1 LASTPIN (-2900 3875) BN 1
J 2
(-2848 3883);
DISPLAY 0.617021 (-2848 3883);
PAINT GREEN (-2848 3883);
FORCEPROP 2 LAST CDS_LIB mstr_standard
J 0
(-2850 3875);
PAINT MONO (-2850 3875);
DISPLAY INVISIBLE (-2850 3875);
FORCEPROP 1 LAST BODY_TYPE PLUMBING
J 2
(-2850 3825);
DISPLAY 1.595745 (-2850 3825);
PAINT GREEN (-2850 3825);
DISPLAY INVISIBLE (-2850 3825);
FORCEPROP 1 LAST HDL_TAP TRUE
J 2
(-3175 3750);
DISPLAY 1.595745 (-3175 3750);
PAINT GREEN (-3175 3750);
DISPLAY INVISIBLE (-3175 3750);
FORCEPROP 1 LAST PATH I144
J 2
(-2848 3875);
DISPLAY 0.872340 (-2848 3875);
PAINT GREEN (-2848 3875);
DISPLAY INVISIBLE (-2848 3875);
FORCEADD TAP..6
R 2
(-2850 3925);
FORCEPROP 3 LASTPIN (-2900 3925) SIG_NAME M_L_DQS_DP<2>
J 0
(-2890 3935);
DISPLAY 0.659574 (-2890 3935);
PAINT MONO (-2890 3935);
DISPLAY INVISIBLE (-2890 3935);
FORCEPROP 1 LASTPIN (-2900 3925) BN 2
J 2
(-2848 3933);
DISPLAY 0.617021 (-2848 3933);
PAINT GREEN (-2848 3933);
FORCEPROP 2 LAST CDS_LIB mstr_standard
J 0
(-2850 3925);
PAINT MONO (-2850 3925);
DISPLAY INVISIBLE (-2850 3925);
FORCEPROP 1 LAST BODY_TYPE PLUMBING
J 2
(-2850 3875);
DISPLAY 1.595745 (-2850 3875);
PAINT GREEN (-2850 3875);
DISPLAY INVISIBLE (-2850 3875);
FORCEPROP 1 LAST HDL_TAP TRUE
J 2
(-3175 3800);
DISPLAY 1.595745 (-3175 3800);
PAINT GREEN (-3175 3800);
DISPLAY INVISIBLE (-3175 3800);
FORCEPROP 1 LAST PATH I145
J 2
(-2848 3925);
DISPLAY 0.872340 (-2848 3925);
PAINT GREEN (-2848 3925);
DISPLAY INVISIBLE (-2848 3925);
FORCEADD TAP..6
R 2
(-2850 3975);
FORCEPROP 3 LASTPIN (-2900 3975) SIG_NAME M_L_DQS_DP<3>
J 0
(-2890 3985);
DISPLAY 0.659574 (-2890 3985);
PAINT MONO (-2890 3985);
DISPLAY INVISIBLE (-2890 3985);
FORCEPROP 1 LASTPIN (-2900 3975) BN 3
J 2
(-2848 3983);
DISPLAY 0.617021 (-2848 3983);
PAINT GREEN (-2848 3983);
FORCEPROP 2 LAST CDS_LIB mstr_standard
J 0
(-2850 3975);
PAINT MONO (-2850 3975);
DISPLAY INVISIBLE (-2850 3975);
FORCEPROP 1 LAST BODY_TYPE PLUMBING
J 2
(-2850 3925);
DISPLAY 1.595745 (-2850 3925);
PAINT GREEN (-2850 3925);
DISPLAY INVISIBLE (-2850 3925);
FORCEPROP 1 LAST HDL_TAP TRUE
J 2
(-3175 3850);
DISPLAY 1.595745 (-3175 3850);
PAINT GREEN (-3175 3850);
DISPLAY INVISIBLE (-3175 3850);
FORCEPROP 1 LAST PATH I146
J 2
(-2848 3975);
DISPLAY 0.872340 (-2848 3975);
PAINT GREEN (-2848 3975);
DISPLAY INVISIBLE (-2848 3975);
FORCEADD OFFPAGE..2
(-1975 525);
FORCEPROP 2 LAST $XR0 85 
J 0
(-1786 525);
DISPLAY 0.638298 (-1786 525);
PAINT MONO (-1786 525);
FORCEPROP 2 LAST $XR1 86 
J 0
(-1696 525);
DISPLAY 0.638298 (-1696 525);
PAINT MONO (-1696 525);
FORCEPROP 2 LAST CDS_LIB mstr_standard
J 0
(-1975 525);
PAINT MONO (-1975 525);
DISPLAY INVISIBLE (-1975 525);
FORCEPROP 1 LAST OFFPAGE TRUE
J 0
(-1650 400);
DISPLAY 1.170213 (-1650 400);
PAINT GREEN (-1650 400);
DISPLAY INVISIBLE (-1650 400);
FORCEPROP 1 LAST COMMENT_BODY TRUE
J 0
(-2020 430);
DISPLAY 1.170213 (-2020 430);
PAINT GREEN (-2020 430);
DISPLAY INVISIBLE (-2020 430);
FORCEPROP 2 LAST PATH I147
J 0
(-1800 600);
DISPLAY 1.021277 (-1800 600);
PAINT ORANGE (-1800 600);
DISPLAY INVISIBLE (-1800 600);
FORCEADD OFFPAGE..4
(-1975 575);
FORCEPROP 2 LAST $XR0 85 
J 0
(-1789 575);
DISPLAY 0.638298 (-1789 575);
PAINT MONO (-1789 575);
FORCEPROP 2 LAST $XR1 86 
J 0
(-1699 575);
DISPLAY 0.638298 (-1699 575);
PAINT MONO (-1699 575);
FORCEPROP 2 LAST CDS_LIB mstr_standard
J 0
(-1975 575);
PAINT MONO (-1975 575);
DISPLAY INVISIBLE (-1975 575);
FORCEPROP 1 LAST OFFPAGE TRUE
J 0
(-1650 450);
DISPLAY 1.170213 (-1650 450);
PAINT GREEN (-1650 450);
DISPLAY INVISIBLE (-1650 450);
FORCEPROP 1 LAST COMMENT_BODY TRUE
J 0
(-2000 475);
DISPLAY 1.170213 (-2000 475);
PAINT GREEN (-2000 475);
DISPLAY INVISIBLE (-2000 475);
FORCEPROP 2 LAST PATH I148
J 0
(-1800 650);
DISPLAY 1.021277 (-1800 650);
PAINT ORANGE (-1800 650);
DISPLAY INVISIBLE (-1800 650);
FORCEADD OFFPAGE..2
(-1975 625);
FORCEPROP 2 LAST $XR0 85 
J 0
(-1786 625);
DISPLAY 0.638298 (-1786 625);
PAINT MONO (-1786 625);
FORCEPROP 2 LAST $XR1 86 
J 0
(-1696 625);
DISPLAY 0.638298 (-1696 625);
PAINT MONO (-1696 625);
FORCEPROP 2 LAST CDS_LIB mstr_standard
J 0
(-1975 625);
PAINT MONO (-1975 625);
DISPLAY INVISIBLE (-1975 625);
FORCEPROP 1 LAST OFFPAGE TRUE
J 0
(-1650 500);
DISPLAY 1.170213 (-1650 500);
PAINT GREEN (-1650 500);
DISPLAY INVISIBLE (-1650 500);
FORCEPROP 1 LAST COMMENT_BODY TRUE
J 0
(-2020 530);
DISPLAY 1.170213 (-2020 530);
PAINT GREEN (-2020 530);
DISPLAY INVISIBLE (-2020 530);
FORCEPROP 2 LAST PATH I149
J 0
(-1800 700);
DISPLAY 1.021277 (-1800 700);
PAINT ORANGE (-1800 700);
DISPLAY INVISIBLE (-1800 700);
FORCEADD TAP..6
(-5575 1175);
FORCEPROP 3 LASTPIN (-5525 1175) SIG_NAME M_L_ECC<2>
J 0
(-5515 1185);
DISPLAY 0.659574 (-5515 1185);
PAINT MONO (-5515 1185);
DISPLAY INVISIBLE (-5515 1185);
FORCEPROP 1 LASTPIN (-5525 1175) BN 2
J 0
(-5577 1183);
DISPLAY 0.617021 (-5577 1183);
PAINT GREEN (-5577 1183);
FORCEPROP 2 LAST CDS_LIB mstr_standard
J 0
(-5575 1175);
PAINT MONO (-5575 1175);
DISPLAY INVISIBLE (-5575 1175);
FORCEPROP 1 LAST BODY_TYPE PLUMBING
J 0
(-5575 1125);
DISPLAY 1.595745 (-5575 1125);
PAINT GREEN (-5575 1125);
DISPLAY INVISIBLE (-5575 1125);
FORCEPROP 1 LAST HDL_TAP TRUE
J 0
(-5250 1050);
DISPLAY 1.595745 (-5250 1050);
PAINT GREEN (-5250 1050);
DISPLAY INVISIBLE (-5250 1050);
FORCEPROP 1 LAST PATH I15
J 0
(-5577 1175);
DISPLAY 0.872340 (-5577 1175);
PAINT GREEN (-5577 1175);
DISPLAY INVISIBLE (-5577 1175);
FORCEADD OFFPAGE..2
(-2000 825);
FORCEPROP 2 LAST $XR0 85 
J 0
(-1811 825);
DISPLAY 0.638298 (-1811 825);
PAINT MONO (-1811 825);
FORCEPROP 2 LAST $XR1 86 
J 0
(-1721 825);
DISPLAY 0.638298 (-1721 825);
PAINT MONO (-1721 825);
FORCEPROP 2 LAST CDS_LIB mstr_standard
J 0
(-2000 825);
PAINT MONO (-2000 825);
DISPLAY INVISIBLE (-2000 825);
FORCEPROP 1 LAST OFFPAGE TRUE
J 0
(-1675 700);
DISPLAY 1.170213 (-1675 700);
PAINT GREEN (-1675 700);
DISPLAY INVISIBLE (-1675 700);
FORCEPROP 1 LAST COMMENT_BODY TRUE
J 0
(-2045 730);
DISPLAY 1.170213 (-2045 730);
PAINT GREEN (-2045 730);
DISPLAY INVISIBLE (-2045 730);
FORCEPROP 2 LAST PATH I150
J 0
(-1825 900);
DISPLAY 1.021277 (-1825 900);
PAINT ORANGE (-1825 900);
DISPLAY INVISIBLE (-1825 900);
FORCEADD OFFPAGE..2
(-2000 925);
FORCEPROP 2 LAST $XR0 85 
J 0
(-1811 925);
DISPLAY 0.638298 (-1811 925);
PAINT MONO (-1811 925);
FORCEPROP 2 LAST $XR1 86 
J 0
(-1721 925);
DISPLAY 0.638298 (-1721 925);
PAINT MONO (-1721 925);
FORCEPROP 2 LAST CDS_LIB mstr_standard
J 0
(-2000 925);
PAINT MONO (-2000 925);
DISPLAY INVISIBLE (-2000 925);
FORCEPROP 1 LAST OFFPAGE TRUE
J 0
(-1675 800);
DISPLAY 1.170213 (-1675 800);
PAINT GREEN (-1675 800);
DISPLAY INVISIBLE (-1675 800);
FORCEPROP 1 LAST COMMENT_BODY TRUE
J 0
(-2045 830);
DISPLAY 1.170213 (-2045 830);
PAINT GREEN (-2045 830);
DISPLAY INVISIBLE (-2045 830);
FORCEPROP 2 LAST PATH I151
J 0
(-1825 1000);
DISPLAY 1.021277 (-1825 1000);
PAINT ORANGE (-1825 1000);
DISPLAY INVISIBLE (-1825 1000);
FORCEADD OFFPAGE..2
(-2000 1375);
FORCEPROP 2 LAST $XR0 85 
J 0
(-1811 1375);
DISPLAY 0.638298 (-1811 1375);
PAINT MONO (-1811 1375);
FORCEPROP 2 LAST $XR1 86 
J 0
(-1721 1375);
DISPLAY 0.638298 (-1721 1375);
PAINT MONO (-1721 1375);
FORCEPROP 2 LAST CDS_LIB mstr_standard
J 0
(-2000 1375);
PAINT MONO (-2000 1375);
DISPLAY INVISIBLE (-2000 1375);
FORCEPROP 1 LAST OFFPAGE TRUE
J 0
(-1675 1250);
DISPLAY 1.170213 (-1675 1250);
PAINT GREEN (-1675 1250);
DISPLAY INVISIBLE (-1675 1250);
FORCEPROP 1 LAST COMMENT_BODY TRUE
J 0
(-2045 1280);
DISPLAY 1.170213 (-2045 1280);
PAINT GREEN (-2045 1280);
DISPLAY INVISIBLE (-2045 1280);
FORCEPROP 2 LAST PATH I152
J 0
(-1825 1450);
DISPLAY 1.021277 (-1825 1450);
PAINT ORANGE (-1825 1450);
DISPLAY INVISIBLE (-1825 1450);
FORCEADD OFFPAGE..2
(-2000 1625);
FORCEPROP 2 LAST $XR0 85 
J 0
(-1811 1625);
DISPLAY 0.638298 (-1811 1625);
PAINT MONO (-1811 1625);
FORCEPROP 2 LAST $XR1 86 
J 0
(-1721 1625);
DISPLAY 0.638298 (-1721 1625);
PAINT MONO (-1721 1625);
FORCEPROP 2 LAST CDS_LIB mstr_standard
J 0
(-2000 1625);
PAINT MONO (-2000 1625);
DISPLAY INVISIBLE (-2000 1625);
FORCEPROP 1 LAST OFFPAGE TRUE
J 0
(-1675 1500);
DISPLAY 1.170213 (-1675 1500);
PAINT GREEN (-1675 1500);
DISPLAY INVISIBLE (-1675 1500);
FORCEPROP 1 LAST COMMENT_BODY TRUE
J 0
(-2045 1530);
DISPLAY 1.170213 (-2045 1530);
PAINT GREEN (-2045 1530);
DISPLAY INVISIBLE (-2045 1530);
FORCEPROP 2 LAST PATH I153
J 0
(-1825 1700);
DISPLAY 1.021277 (-1825 1700);
PAINT ORANGE (-1825 1700);
DISPLAY INVISIBLE (-1825 1700);
FORCEADD OFFPAGE..2
(-2000 1875);
FORCEPROP 2 LAST $XR0 85 
J 0
(-1811 1875);
DISPLAY 0.638298 (-1811 1875);
PAINT MONO (-1811 1875);
FORCEPROP 2 LAST $XR1 86 
J 0
(-1721 1875);
DISPLAY 0.638298 (-1721 1875);
PAINT MONO (-1721 1875);
FORCEPROP 2 LAST CDS_LIB mstr_standard
J 0
(-2000 1875);
PAINT MONO (-2000 1875);
DISPLAY INVISIBLE (-2000 1875);
FORCEPROP 1 LAST OFFPAGE TRUE
J 0
(-1675 1750);
DISPLAY 1.170213 (-1675 1750);
PAINT GREEN (-1675 1750);
DISPLAY INVISIBLE (-1675 1750);
FORCEPROP 1 LAST COMMENT_BODY TRUE
J 0
(-2045 1780);
DISPLAY 1.170213 (-2045 1780);
PAINT GREEN (-2045 1780);
DISPLAY INVISIBLE (-2045 1780);
FORCEPROP 2 LAST PATH I154
J 0
(-1825 1950);
DISPLAY 1.021277 (-1825 1950);
PAINT ORANGE (-1825 1950);
DISPLAY INVISIBLE (-1825 1950);
FORCEADD OFFPAGE..2
(-2000 2825);
FORCEPROP 2 LAST $XR0 85 
J 0
(-1811 2825);
DISPLAY 0.638298 (-1811 2825);
PAINT MONO (-1811 2825);
FORCEPROP 2 LAST $XR1 86 
J 0
(-1721 2825);
DISPLAY 0.638298 (-1721 2825);
PAINT MONO (-1721 2825);
FORCEPROP 2 LAST CDS_LIB mstr_standard
J 0
(-2000 2825);
PAINT MONO (-2000 2825);
DISPLAY INVISIBLE (-2000 2825);
FORCEPROP 1 LAST OFFPAGE TRUE
J 0
(-1675 2700);
DISPLAY 1.170213 (-1675 2700);
PAINT GREEN (-1675 2700);
DISPLAY INVISIBLE (-1675 2700);
FORCEPROP 1 LAST COMMENT_BODY TRUE
J 0
(-2045 2730);
DISPLAY 1.170213 (-2045 2730);
PAINT GREEN (-2045 2730);
DISPLAY INVISIBLE (-2045 2730);
FORCEPROP 2 LAST PATH I155
J 0
(-1825 2900);
DISPLAY 1.021277 (-1825 2900);
PAINT ORANGE (-1825 2900);
DISPLAY INVISIBLE (-1825 2900);
FORCEADD OFFPAGE..3
(-2000 3775);
FORCEPROP 2 LAST $XR0 85 
J 0
(-1786 3775);
DISPLAY 0.638298 (-1786 3775);
PAINT MONO (-1786 3775);
FORCEPROP 2 LAST $XR1 86 
J 0
(-1696 3775);
DISPLAY 0.638298 (-1696 3775);
PAINT MONO (-1696 3775);
FORCEPROP 2 LAST CDS_LIB mstr_standard
J 0
(-2000 3775);
PAINT MONO (-2000 3775);
DISPLAY INVISIBLE (-2000 3775);
FORCEPROP 1 LAST OFFPAGE TRUE
J 0
(-1675 3650);
DISPLAY 1.170213 (-1675 3650);
PAINT GREEN (-1675 3650);
DISPLAY INVISIBLE (-1675 3650);
FORCEPROP 1 LAST COMMENT_BODY TRUE
J 0
(-2050 3675);
DISPLAY 1.170213 (-2050 3675);
PAINT GREEN (-2050 3675);
DISPLAY INVISIBLE (-2050 3675);
FORCEPROP 2 LAST PATH I156
J 0
(-1800 3850);
DISPLAY 1.021277 (-1800 3850);
PAINT ORANGE (-1800 3850);
DISPLAY INVISIBLE (-1800 3850);
FORCEADD TAP..6
R 2
(-2850 4025);
FORCEPROP 3 LASTPIN (-2900 4025) SIG_NAME M_L_DQS_DP<4>
J 0
(-2890 4035);
DISPLAY 0.659574 (-2890 4035);
PAINT MONO (-2890 4035);
DISPLAY INVISIBLE (-2890 4035);
FORCEPROP 1 LASTPIN (-2900 4025) BN 4
J 2
(-2848 4033);
DISPLAY 0.617021 (-2848 4033);
PAINT GREEN (-2848 4033);
FORCEPROP 2 LAST CDS_LIB mstr_standard
J 0
(-2850 4025);
PAINT MONO (-2850 4025);
DISPLAY INVISIBLE (-2850 4025);
FORCEPROP 1 LAST BODY_TYPE PLUMBING
J 2
(-2850 3975);
DISPLAY 1.595745 (-2850 3975);
PAINT GREEN (-2850 3975);
DISPLAY INVISIBLE (-2850 3975);
FORCEPROP 1 LAST HDL_TAP TRUE
J 2
(-3175 3900);
DISPLAY 1.595745 (-3175 3900);
PAINT GREEN (-3175 3900);
DISPLAY INVISIBLE (-3175 3900);
FORCEPROP 1 LAST PATH I157
J 2
(-2848 4025);
DISPLAY 0.872340 (-2848 4025);
PAINT GREEN (-2848 4025);
DISPLAY INVISIBLE (-2848 4025);
FORCEADD TAP..6
R 2
(-2850 4125);
FORCEPROP 3 LASTPIN (-2900 4125) SIG_NAME M_L_DQS_DP<6>
J 0
(-2890 4135);
DISPLAY 0.659574 (-2890 4135);
PAINT MONO (-2890 4135);
DISPLAY INVISIBLE (-2890 4135);
FORCEPROP 1 LASTPIN (-2900 4125) BN 6
J 2
(-2848 4133);
DISPLAY 0.617021 (-2848 4133);
PAINT GREEN (-2848 4133);
FORCEPROP 2 LAST CDS_LIB mstr_standard
J 0
(-2850 4125);
PAINT MONO (-2850 4125);
DISPLAY INVISIBLE (-2850 4125);
FORCEPROP 1 LAST BODY_TYPE PLUMBING
J 2
(-2850 4075);
DISPLAY 1.595745 (-2850 4075);
PAINT GREEN (-2850 4075);
DISPLAY INVISIBLE (-2850 4075);
FORCEPROP 1 LAST HDL_TAP TRUE
J 2
(-3175 4000);
DISPLAY 1.595745 (-3175 4000);
PAINT GREEN (-3175 4000);
DISPLAY INVISIBLE (-3175 4000);
FORCEPROP 1 LAST PATH I158
J 2
(-2848 4125);
DISPLAY 0.872340 (-2848 4125);
PAINT GREEN (-2848 4125);
DISPLAY INVISIBLE (-2848 4125);
FORCEADD TAP..6
R 2
(-2850 4075);
FORCEPROP 3 LASTPIN (-2900 4075) SIG_NAME M_L_DQS_DP<5>
J 0
(-2890 4085);
DISPLAY 0.659574 (-2890 4085);
PAINT MONO (-2890 4085);
DISPLAY INVISIBLE (-2890 4085);
FORCEPROP 1 LASTPIN (-2900 4075) BN 5
J 2
(-2848 4083);
DISPLAY 0.617021 (-2848 4083);
PAINT GREEN (-2848 4083);
FORCEPROP 2 LAST CDS_LIB mstr_standard
J 0
(-2850 4075);
PAINT MONO (-2850 4075);
DISPLAY INVISIBLE (-2850 4075);
FORCEPROP 1 LAST BODY_TYPE PLUMBING
J 2
(-2850 4025);
DISPLAY 1.595745 (-2850 4025);
PAINT GREEN (-2850 4025);
DISPLAY INVISIBLE (-2850 4025);
FORCEPROP 1 LAST HDL_TAP TRUE
J 2
(-3175 3950);
DISPLAY 1.595745 (-3175 3950);
PAINT GREEN (-3175 3950);
DISPLAY INVISIBLE (-3175 3950);
FORCEPROP 1 LAST PATH I159
J 2
(-2848 4075);
DISPLAY 0.872340 (-2848 4075);
PAINT GREEN (-2848 4075);
DISPLAY INVISIBLE (-2848 4075);
FORCEADD TAP..6
(-5575 1275);
FORCEPROP 3 LASTPIN (-5525 1275) SIG_NAME M_L_ECC<4>
J 0
(-5515 1285);
DISPLAY 0.659574 (-5515 1285);
PAINT MONO (-5515 1285);
DISPLAY INVISIBLE (-5515 1285);
FORCEPROP 1 LASTPIN (-5525 1275) BN 4
J 0
(-5577 1283);
DISPLAY 0.617021 (-5577 1283);
PAINT GREEN (-5577 1283);
FORCEPROP 2 LAST CDS_LIB mstr_standard
J 0
(-5575 1275);
PAINT MONO (-5575 1275);
DISPLAY INVISIBLE (-5575 1275);
FORCEPROP 1 LAST BODY_TYPE PLUMBING
J 0
(-5575 1225);
DISPLAY 1.595745 (-5575 1225);
PAINT GREEN (-5575 1225);
DISPLAY INVISIBLE (-5575 1225);
FORCEPROP 1 LAST HDL_TAP TRUE
J 0
(-5250 1150);
DISPLAY 1.595745 (-5250 1150);
PAINT GREEN (-5250 1150);
DISPLAY INVISIBLE (-5250 1150);
FORCEPROP 1 LAST PATH I16
J 0
(-5577 1275);
DISPLAY 0.872340 (-5577 1275);
PAINT GREEN (-5577 1275);
DISPLAY INVISIBLE (-5577 1275);
FORCEADD TAP..6
R 2
(-2850 4175);
FORCEPROP 3 LASTPIN (-2900 4175) SIG_NAME M_L_DQS_DP<7>
J 0
(-2890 4185);
DISPLAY 0.659574 (-2890 4185);
PAINT MONO (-2890 4185);
DISPLAY INVISIBLE (-2890 4185);
FORCEPROP 1 LASTPIN (-2900 4175) BN 7
J 2
(-2848 4183);
DISPLAY 0.617021 (-2848 4183);
PAINT GREEN (-2848 4183);
FORCEPROP 2 LAST CDS_LIB mstr_standard
J 0
(-2850 4175);
PAINT MONO (-2850 4175);
DISPLAY INVISIBLE (-2850 4175);
FORCEPROP 1 LAST BODY_TYPE PLUMBING
J 2
(-2850 4125);
DISPLAY 1.595745 (-2850 4125);
PAINT GREEN (-2850 4125);
DISPLAY INVISIBLE (-2850 4125);
FORCEPROP 1 LAST HDL_TAP TRUE
J 2
(-3175 4050);
DISPLAY 1.595745 (-3175 4050);
PAINT GREEN (-3175 4050);
DISPLAY INVISIBLE (-3175 4050);
FORCEPROP 1 LAST PATH I160
J 2
(-2848 4175);
DISPLAY 0.872340 (-2848 4175);
PAINT GREEN (-2848 4175);
DISPLAY INVISIBLE (-2848 4175);
FORCEADD TAP..6
R 2
(-2850 4225);
FORCEPROP 3 LASTPIN (-2900 4225) SIG_NAME M_L_DQS_DP<8>
J 0
(-2890 4235);
DISPLAY 0.659574 (-2890 4235);
PAINT MONO (-2890 4235);
DISPLAY INVISIBLE (-2890 4235);
FORCEPROP 1 LASTPIN (-2900 4225) BN 8
J 2
(-2848 4233);
DISPLAY 0.617021 (-2848 4233);
PAINT GREEN (-2848 4233);
FORCEPROP 2 LAST CDS_LIB mstr_standard
J 0
(-2850 4225);
PAINT MONO (-2850 4225);
DISPLAY INVISIBLE (-2850 4225);
FORCEPROP 1 LAST BODY_TYPE PLUMBING
J 2
(-2850 4175);
DISPLAY 1.595745 (-2850 4175);
PAINT GREEN (-2850 4175);
DISPLAY INVISIBLE (-2850 4175);
FORCEPROP 1 LAST HDL_TAP TRUE
J 2
(-3175 4100);
DISPLAY 1.595745 (-3175 4100);
PAINT GREEN (-3175 4100);
DISPLAY INVISIBLE (-3175 4100);
FORCEPROP 1 LAST PATH I161
J 2
(-2848 4225);
DISPLAY 0.872340 (-2848 4225);
PAINT GREEN (-2848 4225);
DISPLAY INVISIBLE (-2848 4225);
FORCEADD TAP..6
R 2
(-2850 4275);
FORCEPROP 3 LASTPIN (-2900 4275) SIG_NAME M_L_DQS_DP<9>
J 0
(-2890 4285);
DISPLAY 0.659574 (-2890 4285);
PAINT MONO (-2890 4285);
DISPLAY INVISIBLE (-2890 4285);
FORCEPROP 1 LASTPIN (-2900 4275) BN 9
J 2
(-2848 4283);
DISPLAY 0.617021 (-2848 4283);
PAINT GREEN (-2848 4283);
FORCEPROP 2 LAST CDS_LIB mstr_standard
J 0
(-2850 4275);
PAINT MONO (-2850 4275);
DISPLAY INVISIBLE (-2850 4275);
FORCEPROP 1 LAST BODY_TYPE PLUMBING
J 2
(-2850 4225);
DISPLAY 1.595745 (-2850 4225);
PAINT GREEN (-2850 4225);
DISPLAY INVISIBLE (-2850 4225);
FORCEPROP 1 LAST HDL_TAP TRUE
J 2
(-3175 4150);
DISPLAY 1.595745 (-3175 4150);
PAINT GREEN (-3175 4150);
DISPLAY INVISIBLE (-3175 4150);
FORCEPROP 1 LAST PATH I162
J 2
(-2848 4275);
DISPLAY 0.872340 (-2848 4275);
PAINT GREEN (-2848 4275);
DISPLAY INVISIBLE (-2848 4275);
FORCEADD TAP..6
R 2
(-2850 4325);
FORCEPROP 3 LASTPIN (-2900 4325) SIG_NAME M_L_DQS_DP<10>
J 0
(-2890 4335);
DISPLAY 0.659574 (-2890 4335);
PAINT MONO (-2890 4335);
DISPLAY INVISIBLE (-2890 4335);
FORCEPROP 1 LASTPIN (-2900 4325) BN 10
J 2
(-2848 4333);
DISPLAY 0.617021 (-2848 4333);
PAINT GREEN (-2848 4333);
FORCEPROP 2 LAST CDS_LIB mstr_standard
J 0
(-2850 4325);
PAINT MONO (-2850 4325);
DISPLAY INVISIBLE (-2850 4325);
FORCEPROP 1 LAST BODY_TYPE PLUMBING
J 2
(-2850 4275);
DISPLAY 1.595745 (-2850 4275);
PAINT GREEN (-2850 4275);
DISPLAY INVISIBLE (-2850 4275);
FORCEPROP 1 LAST HDL_TAP TRUE
J 2
(-3175 4200);
DISPLAY 1.595745 (-3175 4200);
PAINT GREEN (-3175 4200);
DISPLAY INVISIBLE (-3175 4200);
FORCEPROP 1 LAST PATH I163
J 2
(-2848 4325);
DISPLAY 0.872340 (-2848 4325);
PAINT GREEN (-2848 4325);
DISPLAY INVISIBLE (-2848 4325);
FORCEADD TAP..6
R 2
(-2850 4375);
FORCEPROP 3 LASTPIN (-2900 4375) SIG_NAME M_L_DQS_DP<11>
J 0
(-2890 4385);
DISPLAY 0.659574 (-2890 4385);
PAINT MONO (-2890 4385);
DISPLAY INVISIBLE (-2890 4385);
FORCEPROP 1 LASTPIN (-2900 4375) BN 11
J 2
(-2848 4383);
DISPLAY 0.617021 (-2848 4383);
PAINT GREEN (-2848 4383);
FORCEPROP 2 LAST CDS_LIB mstr_standard
J 0
(-2850 4375);
PAINT MONO (-2850 4375);
DISPLAY INVISIBLE (-2850 4375);
FORCEPROP 1 LAST BODY_TYPE PLUMBING
J 2
(-2850 4325);
DISPLAY 1.595745 (-2850 4325);
PAINT GREEN (-2850 4325);
DISPLAY INVISIBLE (-2850 4325);
FORCEPROP 1 LAST HDL_TAP TRUE
J 2
(-3175 4250);
DISPLAY 1.595745 (-3175 4250);
PAINT GREEN (-3175 4250);
DISPLAY INVISIBLE (-3175 4250);
FORCEPROP 1 LAST PATH I164
J 2
(-2848 4375);
DISPLAY 0.872340 (-2848 4375);
PAINT GREEN (-2848 4375);
DISPLAY INVISIBLE (-2848 4375);
FORCEADD TAP..6
R 2
(-2850 4525);
FORCEPROP 3 LASTPIN (-2900 4525) SIG_NAME M_L_DQS_DP<14>
J 0
(-2890 4535);
DISPLAY 0.659574 (-2890 4535);
PAINT MONO (-2890 4535);
DISPLAY INVISIBLE (-2890 4535);
FORCEPROP 1 LASTPIN (-2900 4525) BN 14
J 2
(-2848 4533);
DISPLAY 0.617021 (-2848 4533);
PAINT GREEN (-2848 4533);
FORCEPROP 2 LAST CDS_LIB mstr_standard
J 0
(-2850 4525);
PAINT MONO (-2850 4525);
DISPLAY INVISIBLE (-2850 4525);
FORCEPROP 1 LAST BODY_TYPE PLUMBING
J 2
(-2850 4475);
DISPLAY 1.595745 (-2850 4475);
PAINT GREEN (-2850 4475);
DISPLAY INVISIBLE (-2850 4475);
FORCEPROP 1 LAST HDL_TAP TRUE
J 2
(-3175 4400);
DISPLAY 1.595745 (-3175 4400);
PAINT GREEN (-3175 4400);
DISPLAY INVISIBLE (-3175 4400);
FORCEPROP 1 LAST PATH I165
J 2
(-2848 4525);
DISPLAY 0.872340 (-2848 4525);
PAINT GREEN (-2848 4525);
DISPLAY INVISIBLE (-2848 4525);
FORCEADD TAP..6
R 2
(-2850 4475);
FORCEPROP 3 LASTPIN (-2900 4475) SIG_NAME M_L_DQS_DP<13>
J 0
(-2890 4485);
DISPLAY 0.659574 (-2890 4485);
PAINT MONO (-2890 4485);
DISPLAY INVISIBLE (-2890 4485);
FORCEPROP 1 LASTPIN (-2900 4475) BN 13
J 2
(-2848 4483);
DISPLAY 0.617021 (-2848 4483);
PAINT GREEN (-2848 4483);
FORCEPROP 2 LAST CDS_LIB mstr_standard
J 0
(-2850 4475);
PAINT MONO (-2850 4475);
DISPLAY INVISIBLE (-2850 4475);
FORCEPROP 1 LAST BODY_TYPE PLUMBING
J 2
(-2850 4425);
DISPLAY 1.595745 (-2850 4425);
PAINT GREEN (-2850 4425);
DISPLAY INVISIBLE (-2850 4425);
FORCEPROP 1 LAST HDL_TAP TRUE
J 2
(-3175 4350);
DISPLAY 1.595745 (-3175 4350);
PAINT GREEN (-3175 4350);
DISPLAY INVISIBLE (-3175 4350);
FORCEPROP 1 LAST PATH I166
J 2
(-2848 4475);
DISPLAY 0.872340 (-2848 4475);
PAINT GREEN (-2848 4475);
DISPLAY INVISIBLE (-2848 4475);
FORCEADD TAP..6
R 2
(-2850 4425);
FORCEPROP 3 LASTPIN (-2900 4425) SIG_NAME M_L_DQS_DP<12>
J 0
(-2890 4435);
DISPLAY 0.659574 (-2890 4435);
PAINT MONO (-2890 4435);
DISPLAY INVISIBLE (-2890 4435);
FORCEPROP 1 LASTPIN (-2900 4425) BN 12
J 2
(-2848 4433);
DISPLAY 0.617021 (-2848 4433);
PAINT GREEN (-2848 4433);
FORCEPROP 2 LAST CDS_LIB mstr_standard
J 0
(-2850 4425);
PAINT MONO (-2850 4425);
DISPLAY INVISIBLE (-2850 4425);
FORCEPROP 1 LAST BODY_TYPE PLUMBING
J 2
(-2850 4375);
DISPLAY 1.595745 (-2850 4375);
PAINT GREEN (-2850 4375);
DISPLAY INVISIBLE (-2850 4375);
FORCEPROP 1 LAST HDL_TAP TRUE
J 2
(-3175 4300);
DISPLAY 1.595745 (-3175 4300);
PAINT GREEN (-3175 4300);
DISPLAY INVISIBLE (-3175 4300);
FORCEPROP 1 LAST PATH I167
J 2
(-2848 4425);
DISPLAY 0.872340 (-2848 4425);
PAINT GREEN (-2848 4425);
DISPLAY INVISIBLE (-2848 4425);
FORCEADD TAP..6
R 2
(-2850 4575);
FORCEPROP 3 LASTPIN (-2900 4575) SIG_NAME M_L_DQS_DP<15>
J 0
(-2890 4585);
DISPLAY 0.659574 (-2890 4585);
PAINT MONO (-2890 4585);
DISPLAY INVISIBLE (-2890 4585);
FORCEPROP 1 LASTPIN (-2900 4575) BN 15
J 2
(-2848 4583);
DISPLAY 0.617021 (-2848 4583);
PAINT GREEN (-2848 4583);
FORCEPROP 2 LAST CDS_LIB mstr_standard
J 0
(-2850 4575);
PAINT MONO (-2850 4575);
DISPLAY INVISIBLE (-2850 4575);
FORCEPROP 1 LAST BODY_TYPE PLUMBING
J 2
(-2850 4525);
DISPLAY 1.595745 (-2850 4525);
PAINT GREEN (-2850 4525);
DISPLAY INVISIBLE (-2850 4525);
FORCEPROP 1 LAST HDL_TAP TRUE
J 2
(-3175 4450);
DISPLAY 1.595745 (-3175 4450);
PAINT GREEN (-3175 4450);
DISPLAY INVISIBLE (-3175 4450);
FORCEPROP 1 LAST PATH I168
J 2
(-2848 4575);
DISPLAY 0.872340 (-2848 4575);
PAINT GREEN (-2848 4575);
DISPLAY INVISIBLE (-2848 4575);
FORCEADD TAP..6
R 2
(-2850 4625);
FORCEPROP 3 LASTPIN (-2900 4625) SIG_NAME M_L_DQS_DP<16>
J 0
(-2890 4635);
DISPLAY 0.659574 (-2890 4635);
PAINT MONO (-2890 4635);
DISPLAY INVISIBLE (-2890 4635);
FORCEPROP 1 LASTPIN (-2900 4625) BN 16
J 2
(-2848 4633);
DISPLAY 0.617021 (-2848 4633);
PAINT GREEN (-2848 4633);
FORCEPROP 2 LAST CDS_LIB mstr_standard
J 0
(-2850 4625);
PAINT MONO (-2850 4625);
DISPLAY INVISIBLE (-2850 4625);
FORCEPROP 1 LAST BODY_TYPE PLUMBING
J 2
(-2850 4575);
DISPLAY 1.595745 (-2850 4575);
PAINT GREEN (-2850 4575);
DISPLAY INVISIBLE (-2850 4575);
FORCEPROP 1 LAST HDL_TAP TRUE
J 2
(-3175 4500);
DISPLAY 1.595745 (-3175 4500);
PAINT GREEN (-3175 4500);
DISPLAY INVISIBLE (-3175 4500);
FORCEPROP 1 LAST PATH I169
J 2
(-2848 4625);
DISPLAY 0.872340 (-2848 4625);
PAINT GREEN (-2848 4625);
DISPLAY INVISIBLE (-2848 4625);
FORCEADD TAP..6
(-5575 1225);
FORCEPROP 3 LASTPIN (-5525 1225) SIG_NAME M_L_ECC<3>
J 0
(-5515 1235);
DISPLAY 0.659574 (-5515 1235);
PAINT MONO (-5515 1235);
DISPLAY INVISIBLE (-5515 1235);
FORCEPROP 1 LASTPIN (-5525 1225) BN 3
J 0
(-5577 1233);
DISPLAY 0.617021 (-5577 1233);
PAINT GREEN (-5577 1233);
FORCEPROP 2 LAST CDS_LIB mstr_standard
J 0
(-5575 1225);
PAINT MONO (-5575 1225);
DISPLAY INVISIBLE (-5575 1225);
FORCEPROP 1 LAST BODY_TYPE PLUMBING
J 0
(-5575 1175);
DISPLAY 1.595745 (-5575 1175);
PAINT GREEN (-5575 1175);
DISPLAY INVISIBLE (-5575 1175);
FORCEPROP 1 LAST HDL_TAP TRUE
J 0
(-5250 1100);
DISPLAY 1.595745 (-5250 1100);
PAINT GREEN (-5250 1100);
DISPLAY INVISIBLE (-5250 1100);
FORCEPROP 1 LAST PATH I17
J 0
(-5577 1225);
DISPLAY 0.872340 (-5577 1225);
PAINT GREEN (-5577 1225);
DISPLAY INVISIBLE (-5577 1225);
FORCEADD TAP..6
R 2
(-2850 4675);
FORCEPROP 3 LASTPIN (-2900 4675) SIG_NAME M_L_DQS_DP<17>
J 0
(-2890 4685);
DISPLAY 0.659574 (-2890 4685);
PAINT MONO (-2890 4685);
DISPLAY INVISIBLE (-2890 4685);
FORCEPROP 1 LASTPIN (-2900 4675) BN 17
J 2
(-2848 4683);
DISPLAY 0.617021 (-2848 4683);
PAINT GREEN (-2848 4683);
FORCEPROP 2 LAST CDS_LIB mstr_standard
J 2
(-2850 4675);
PAINT MONO (-2850 4675);
DISPLAY INVISIBLE (-2850 4675);
FORCEPROP 1 LAST BODY_TYPE PLUMBING
J 2
(-2850 4625);
DISPLAY 1.595745 (-2850 4625);
PAINT GREEN (-2850 4625);
DISPLAY INVISIBLE (-2850 4625);
FORCEPROP 1 LAST HDL_TAP TRUE
J 2
(-3175 4550);
DISPLAY 1.595745 (-3175 4550);
PAINT GREEN (-3175 4550);
DISPLAY INVISIBLE (-3175 4550);
FORCEPROP 1 LAST PATH I170
J 2
(-2848 4675);
DISPLAY 0.872340 (-2848 4675);
PAINT GREEN (-2848 4675);
DISPLAY INVISIBLE (-2848 4675);
FORCEADD OFFPAGE..3
(-2000 4750);
FORCEPROP 2 LAST $XR0 85 
J 0
(-1786 4750);
DISPLAY 0.638298 (-1786 4750);
PAINT MONO (-1786 4750);
FORCEPROP 2 LAST $XR1 86 
J 0
(-1696 4750);
DISPLAY 0.638298 (-1696 4750);
PAINT MONO (-1696 4750);
FORCEPROP 2 LAST CDS_LIB mstr_standard
J 0
(-2000 4750);
PAINT MONO (-2000 4750);
DISPLAY INVISIBLE (-2000 4750);
FORCEPROP 1 LAST OFFPAGE TRUE
J 0
(-1675 4625);
DISPLAY 1.170213 (-1675 4625);
PAINT GREEN (-1675 4625);
DISPLAY INVISIBLE (-1675 4625);
FORCEPROP 1 LAST COMMENT_BODY TRUE
J 0
(-2050 4650);
DISPLAY 1.170213 (-2050 4650);
PAINT GREEN (-2050 4650);
DISPLAY INVISIBLE (-2050 4650);
FORCEPROP 2 LAST PATH I171
J 0
(-1800 4825);
DISPLAY 1.021277 (-1800 4825);
PAINT ORANGE (-1800 4825);
DISPLAY INVISIBLE (-1800 4825);
FORCEADD SKX_EXT_B..7
(-4175 2575);
FORCEPROP 1 LAST LOCATION U2D1
J 0
(-4975 4925);
DISPLAY 0.617021 (-4975 4925);
PAINT AQUA (-4975 4925);
FORCEPROP 1 LAST PART_NUMBER TBD
J 0
(-4975 325);
DISPLAY 0.617021 (-4975 325);
PAINT BLUE (-4975 325);
FORCEPROP 1 LAST MATERIAL IC
J 0
(-4975 4875);
DISPLAY 0.617021 (-4975 4875);
PAINT SKYBLUE (-4975 4875);
FORCEPROP 2 LASTPIN (-3325 525) $PN DV53
J 0
(-3315 535);
DISPLAY 0.617021 (-3315 535);
PAINT ORANGE (-3315 535);
FORCEPROP 2 LASTPIN (-3325 1575) $PN DM47
J 0
(-3315 1585);
DISPLAY 0.617021 (-3315 1585);
PAINT ORANGE (-3315 1585);
FORCEPROP 2 LASTPIN (-3325 1525) $PN DT49
J 0
(-3315 1535);
DISPLAY 0.617021 (-3315 1535);
PAINT ORANGE (-3315 1535);
FORCEPROP 2 LASTPIN (-3325 1475) $PN DN48
J 0
(-3315 1485);
DISPLAY 0.617021 (-3315 1485);
PAINT ORANGE (-3315 1485);
FORCEPROP 2 LASTPIN (-3325 1425) $PN DR50
J 0
(-3315 1435);
DISPLAY 0.617021 (-3315 1435);
PAINT ORANGE (-3315 1435);
FORCEPROP 2 LASTPIN (-3325 2775) $PN DR48
J 0
(-3315 2785);
DISPLAY 0.617021 (-3315 2785);
PAINT ORANGE (-3315 2785);
FORCEPROP 2 LASTPIN (-3325 2725) $PN DN52
J 0
(-3315 2735);
DISPLAY 0.617021 (-3315 2735);
PAINT ORANGE (-3315 2735);
FORCEPROP 2 LASTPIN (-3325 2675) $PN DR52
J 0
(-3315 2685);
DISPLAY 0.617021 (-3315 2685);
PAINT ORANGE (-3315 2685);
FORCEPROP 2 LASTPIN (-3325 2625) $PN DM51
J 0
(-3315 2635);
DISPLAY 0.617021 (-3315 2635);
PAINT ORANGE (-3315 2635);
FORCEPROP 2 LASTPIN (-3325 2575) $PN DT51
J 0
(-3315 2585);
DISPLAY 0.617021 (-3315 2585);
PAINT ORANGE (-3315 2585);
FORCEPROP 2 LASTPIN (-3325 2525) $PN DN60
J 0
(-3315 2535);
DISPLAY 0.617021 (-3315 2535);
PAINT ORANGE (-3315 2535);
FORCEPROP 2 LASTPIN (-3325 2475) $PN DR60
J 0
(-3315 2485);
DISPLAY 0.617021 (-3315 2485);
PAINT ORANGE (-3315 2485);
FORCEPROP 2 LASTPIN (-3325 2425) $PN DT55
J 0
(-3315 2435);
DISPLAY 0.617021 (-3315 2435);
PAINT ORANGE (-3315 2435);
FORCEPROP 2 LASTPIN (-3325 2375) $PN DV59
J 0
(-3315 2385);
DISPLAY 0.617021 (-3315 2385);
PAINT ORANGE (-3315 2385);
FORCEPROP 2 LASTPIN (-3325 2325) $PN DJ60
J 0
(-3315 2335);
DISPLAY 0.617021 (-3315 2335);
PAINT ORANGE (-3315 2335);
FORCEPROP 2 LASTPIN (-3325 2275) $PN DK61
J 0
(-3315 2285);
DISPLAY 0.617021 (-3315 2285);
PAINT ORANGE (-3315 2285);
FORCEPROP 2 LASTPIN (-3325 2225) $PN DM59
J 0
(-3315 2235);
DISPLAY 0.617021 (-3315 2235);
PAINT ORANGE (-3315 2235);
FORCEPROP 2 LASTPIN (-3325 2175) $PN DN58
J 0
(-3315 2185);
DISPLAY 0.617021 (-3315 2185);
PAINT ORANGE (-3315 2185);
FORCEPROP 2 LASTPIN (-3325 2125) $PN DT59
J 0
(-3315 2135);
DISPLAY 0.617021 (-3315 2135);
PAINT ORANGE (-3315 2135);
FORCEPROP 2 LASTPIN (-3325 2075) $PN DR58
J 0
(-3315 2085);
DISPLAY 0.617021 (-3315 2085);
PAINT ORANGE (-3315 2085);
FORCEPROP 2 LASTPIN (-3325 2025) $PN DV57
J 0
(-3315 2035);
DISPLAY 0.617021 (-3315 2035);
PAINT ORANGE (-3315 2035);
FORCEPROP 2 LASTPIN (-3325 1975) $PN DW58
J 0
(-3315 1985);
DISPLAY 0.617021 (-3315 1985);
PAINT ORANGE (-3315 1985);
FORCEPROP 2 LASTPIN (-3325 1925) $PN DW52
J 0
(-3315 1935);
DISPLAY 0.617021 (-3315 1935);
PAINT ORANGE (-3315 1935);
FORCEPROP 2 LASTPIN (-5025 1425) $PN EA66
J 2
(-5035 1435);
DISPLAY 0.617021 (-5035 1435);
PAINT ORANGE (-5035 1435);
FORCEPROP 2 LASTPIN (-5025 1375) $PN DU66
J 2
(-5035 1385);
DISPLAY 0.617021 (-5035 1385);
PAINT ORANGE (-5035 1385);
FORCEPROP 2 LASTPIN (-5025 1325) $PN DV69
J 2
(-5035 1335);
DISPLAY 0.617021 (-5035 1335);
PAINT ORANGE (-5035 1335);
FORCEPROP 2 LASTPIN (-5025 1275) $PN DU68
J 2
(-5035 1285);
DISPLAY 0.617021 (-5035 1285);
PAINT ORANGE (-5035 1285);
FORCEPROP 2 LASTPIN (-5025 1225) $PN DY65
J 2
(-5035 1235);
DISPLAY 0.617021 (-5035 1235);
PAINT ORANGE (-5035 1235);
FORCEPROP 2 LASTPIN (-5025 1175) $PN DV65
J 2
(-5035 1185);
DISPLAY 0.617021 (-5035 1185);
PAINT ORANGE (-5035 1185);
FORCEPROP 2 LASTPIN (-5025 1125) $PN EA68
J 2
(-5035 1135);
DISPLAY 0.617021 (-5035 1135);
PAINT ORANGE (-5035 1135);
FORCEPROP 2 LASTPIN (-5025 1075) $PN DY69
J 2
(-5035 1085);
DISPLAY 0.617021 (-5035 1085);
PAINT ORANGE (-5035 1085);
FORCEPROP 2 LASTPIN (-3325 4675) $PN DT67
J 0
(-3315 4685);
DISPLAY 0.617021 (-3315 4685);
PAINT ORANGE (-3315 4685);
FORCEPROP 2 LASTPIN (-3325 4625) $PN DE26
J 0
(-3315 4635);
DISPLAY 0.617021 (-3315 4635);
PAINT ORANGE (-3315 4635);
FORCEPROP 2 LASTPIN (-3325 4575) $PN DW26
J 0
(-3315 4585);
DISPLAY 0.617021 (-3315 4585);
PAINT ORANGE (-3315 4585);
FORCEPROP 2 LASTPIN (-3325 4525) $PN DW32
J 0
(-3315 4535);
DISPLAY 0.617021 (-3315 4535);
PAINT ORANGE (-3315 4535);
FORCEPROP 2 LASTPIN (-3325 4475) $PN DM41
J 0
(-3315 4485);
DISPLAY 0.617021 (-3315 4485);
PAINT ORANGE (-3315 4485);
FORCEPROP 2 LASTPIN (-3325 4425) $PN DY73
J 0
(-3315 4435);
DISPLAY 0.617021 (-3315 4435);
PAINT ORANGE (-3315 4435);
FORCEPROP 2 LASTPIN (-3325 4375) $PN DV79
J 0
(-3315 4385);
DISPLAY 0.617021 (-3315 4385);
PAINT ORANGE (-3315 4385);
FORCEPROP 2 LASTPIN (-3325 4325) $PN DD79
J 0
(-3315 4335);
DISPLAY 0.617021 (-3315 4335);
PAINT ORANGE (-3315 4335);
FORCEPROP 2 LASTPIN (-3325 4275) $PN CP79
J 0
(-3315 4285);
DISPLAY 0.617021 (-3315 4285);
PAINT ORANGE (-3315 4285);
FORCEPROP 2 LASTPIN (-3325 4225) $PN DY67
J 0
(-3315 4235);
DISPLAY 0.617021 (-3315 4235);
PAINT ORANGE (-3315 4235);
FORCEPROP 2 LASTPIN (-3325 4175) $PN DJ26
J 0
(-3315 4185);
DISPLAY 0.617021 (-3315 4185);
PAINT ORANGE (-3315 4185);
FORCEPROP 2 LASTPIN (-3325 4125) $PN EC26
J 0
(-3315 4135);
DISPLAY 0.617021 (-3315 4135);
PAINT ORANGE (-3315 4135);
FORCEPROP 2 LASTPIN (-3325 4075) $PN EC32
J 0
(-3315 4085);
DISPLAY 0.617021 (-3315 4085);
PAINT ORANGE (-3315 4085);
FORCEPROP 2 LASTPIN (-3325 4025) $PN DT41
J 0
(-3315 4035);
DISPLAY 0.617021 (-3315 4035);
PAINT ORANGE (-3315 4035);
FORCEPROP 2 LASTPIN (-3325 3975) $PN ED73
J 0
(-3315 3985);
DISPLAY 0.617021 (-3315 3985);
PAINT ORANGE (-3315 3985);
FORCEPROP 2 LASTPIN (-3325 3925) $PN EB79
J 0
(-3315 3935);
DISPLAY 0.617021 (-3315 3935);
PAINT ORANGE (-3315 3935);
FORCEPROP 2 LASTPIN (-3325 3875) $PN DB81
J 0
(-3315 3885);
DISPLAY 0.617021 (-3315 3885);
PAINT ORANGE (-3315 3885);
FORCEPROP 2 LASTPIN (-3325 3825) $PN CM81
J 0
(-3315 3835);
DISPLAY 0.617021 (-3315 3835);
PAINT ORANGE (-3315 3835);
FORCEPROP 2 LASTPIN (-3325 3725) $PN DV67
J 0
(-3315 3735);
DISPLAY 0.617021 (-3315 3735);
PAINT ORANGE (-3315 3735);
FORCEPROP 2 LASTPIN (-3325 3675) $PN DG26
J 0
(-3315 3685);
DISPLAY 0.617021 (-3315 3685);
PAINT ORANGE (-3315 3685);
FORCEPROP 2 LASTPIN (-3325 3625) $PN EA26
J 0
(-3315 3635);
DISPLAY 0.617021 (-3315 3635);
PAINT ORANGE (-3315 3635);
FORCEPROP 2 LASTPIN (-3325 3575) $PN EA32
J 0
(-3315 3585);
DISPLAY 0.617021 (-3315 3585);
PAINT ORANGE (-3315 3585);
FORCEPROP 2 LASTPIN (-3325 3525) $PN DP41
J 0
(-3315 3535);
DISPLAY 0.617021 (-3315 3535);
PAINT ORANGE (-3315 3535);
FORCEPROP 2 LASTPIN (-3325 3475) $PN EB73
J 0
(-3315 3485);
DISPLAY 0.617021 (-3315 3485);
PAINT ORANGE (-3315 3485);
FORCEPROP 2 LASTPIN (-3325 3425) $PN DY79
J 0
(-3315 3435);
DISPLAY 0.617021 (-3315 3435);
PAINT ORANGE (-3315 3435);
FORCEPROP 2 LASTPIN (-3325 3375) $PN DC80
J 0
(-3315 3385);
DISPLAY 0.617021 (-3315 3385);
PAINT ORANGE (-3315 3385);
FORCEPROP 2 LASTPIN (-3325 3325) $PN CN80
J 0
(-3315 3335);
DISPLAY 0.617021 (-3315 3335);
PAINT ORANGE (-3315 3335);
FORCEPROP 2 LASTPIN (-3325 3275) $PN EB67
J 0
(-3315 3285);
DISPLAY 0.617021 (-3315 3285);
PAINT ORANGE (-3315 3285);
FORCEPROP 2 LASTPIN (-3325 3225) $PN DL26
J 0
(-3315 3235);
DISPLAY 0.617021 (-3315 3235);
PAINT ORANGE (-3315 3235);
FORCEPROP 2 LASTPIN (-3325 3175) $PN EE26
J 0
(-3315 3185);
DISPLAY 0.617021 (-3315 3185);
PAINT ORANGE (-3315 3185);
FORCEPROP 2 LASTPIN (-3325 3125) $PN EE32
J 0
(-3315 3135);
DISPLAY 0.617021 (-3315 3135);
PAINT ORANGE (-3315 3135);
FORCEPROP 2 LASTPIN (-3325 3075) $PN DV41
J 0
(-3315 3085);
DISPLAY 0.617021 (-3315 3085);
PAINT ORANGE (-3315 3085);
FORCEPROP 2 LASTPIN (-3325 3025) $PN EF73
J 0
(-3315 3035);
DISPLAY 0.617021 (-3315 3035);
PAINT ORANGE (-3315 3035);
FORCEPROP 2 LASTPIN (-3325 2975) $PN ED79
J 0
(-3315 2985);
DISPLAY 0.617021 (-3315 2985);
PAINT ORANGE (-3315 2985);
FORCEPROP 2 LASTPIN (-3325 2925) $PN DA82
J 0
(-3315 2935);
DISPLAY 0.617021 (-3315 2935);
PAINT ORANGE (-3315 2935);
FORCEPROP 2 LASTPIN (-3325 2875) $PN CL82
J 0
(-3315 2885);
DISPLAY 0.617021 (-3315 2885);
PAINT ORANGE (-3315 2885);
FORCEPROP 2 LASTPIN (-5025 4675) $PN DK25
J 2
(-5035 4685);
DISPLAY 0.617021 (-5035 4685);
PAINT ORANGE (-5035 4685);
FORCEPROP 2 LASTPIN (-5025 4625) $PN DF25
J 2
(-5035 4635);
DISPLAY 0.617021 (-5035 4635);
PAINT ORANGE (-5035 4635);
FORCEPROP 2 LASTPIN (-5025 4575) $PN DJ28
J 2
(-5035 4585);
DISPLAY 0.617021 (-5035 4585);
PAINT ORANGE (-5035 4585);
FORCEPROP 2 LASTPIN (-5025 4525) $PN DG28
J 2
(-5035 4535);
DISPLAY 0.617021 (-5035 4535);
PAINT ORANGE (-5035 4535);
FORCEPROP 2 LASTPIN (-5025 4475) $PN DJ24
J 2
(-5035 4485);
DISPLAY 0.617021 (-5035 4485);
PAINT ORANGE (-5035 4485);
FORCEPROP 2 LASTPIN (-5025 4425) $PN DD25
J 2
(-5035 4435);
DISPLAY 0.617021 (-5035 4435);
PAINT ORANGE (-5035 4435);
FORCEPROP 2 LASTPIN (-5025 4375) $PN DK27
J 2
(-5035 4385);
DISPLAY 0.617021 (-5035 4385);
PAINT ORANGE (-5035 4385);
FORCEPROP 2 LASTPIN (-5025 4325) $PN DF27
J 2
(-5035 4335);
DISPLAY 0.617021 (-5035 4335);
PAINT ORANGE (-5035 4335);
FORCEPROP 2 LASTPIN (-5025 4275) $PN ED25
J 2
(-5035 4285);
DISPLAY 0.617021 (-5035 4285);
PAINT ORANGE (-5035 4285);
FORCEPROP 2 LASTPIN (-5025 4225) $PN DY25
J 2
(-5035 4235);
DISPLAY 0.617021 (-5035 4235);
PAINT ORANGE (-5035 4235);
FORCEPROP 2 LASTPIN (-5025 4175) $PN EA28
J 2
(-5035 4185);
DISPLAY 0.617021 (-5035 4185);
PAINT ORANGE (-5035 4185);
FORCEPROP 2 LASTPIN (-5025 4125) $PN DY27
J 2
(-5035 4135);
DISPLAY 0.617021 (-5035 4135);
PAINT ORANGE (-5035 4135);
FORCEPROP 2 LASTPIN (-5025 4075) $PN EC24
J 2
(-5035 4085);
DISPLAY 0.617021 (-5035 4085);
PAINT ORANGE (-5035 4085);
FORCEPROP 2 LASTPIN (-5025 4025) $PN EA24
J 2
(-5035 4035);
DISPLAY 0.617021 (-5035 4035);
PAINT ORANGE (-5035 4035);
FORCEPROP 2 LASTPIN (-5025 3975) $PN ED27
J 2
(-5035 3985);
DISPLAY 0.617021 (-5035 3985);
PAINT ORANGE (-5035 3985);
FORCEPROP 2 LASTPIN (-5025 3925) $PN EC28
J 2
(-5035 3935);
DISPLAY 0.617021 (-5035 3935);
PAINT ORANGE (-5035 3935);
FORCEPROP 2 LASTPIN (-5025 3875) $PN ED31
J 2
(-5035 3885);
DISPLAY 0.617021 (-5035 3885);
PAINT ORANGE (-5035 3885);
FORCEPROP 2 LASTPIN (-5025 3825) $PN DY31
J 2
(-5035 3835);
DISPLAY 0.617021 (-5035 3835);
PAINT ORANGE (-5035 3835);
FORCEPROP 2 LASTPIN (-5025 3775) $PN EA34
J 2
(-5035 3785);
DISPLAY 0.617021 (-5035 3785);
PAINT ORANGE (-5035 3785);
FORCEPROP 2 LASTPIN (-5025 3725) $PN DY33
J 2
(-5035 3735);
DISPLAY 0.617021 (-5035 3735);
PAINT ORANGE (-5035 3735);
FORCEPROP 2 LASTPIN (-5025 3675) $PN EC30
J 2
(-5035 3685);
DISPLAY 0.617021 (-5035 3685);
PAINT ORANGE (-5035 3685);
FORCEPROP 2 LASTPIN (-5025 3625) $PN EA30
J 2
(-5035 3635);
DISPLAY 0.617021 (-5035 3635);
PAINT ORANGE (-5035 3635);
FORCEPROP 2 LASTPIN (-5025 3575) $PN ED33
J 2
(-5035 3585);
DISPLAY 0.617021 (-5035 3585);
PAINT ORANGE (-5035 3585);
FORCEPROP 2 LASTPIN (-5025 3525) $PN EC34
J 2
(-5035 3535);
DISPLAY 0.617021 (-5035 3535);
PAINT ORANGE (-5035 3535);
FORCEPROP 2 LASTPIN (-5025 3475) $PN DU40
J 2
(-5035 3485);
DISPLAY 0.617021 (-5035 3485);
PAINT ORANGE (-5035 3485);
FORCEPROP 2 LASTPIN (-5025 3425) $PN DN40
J 2
(-5035 3435);
DISPLAY 0.617021 (-5035 3435);
PAINT ORANGE (-5035 3435);
FORCEPROP 2 LASTPIN (-5025 3375) $PN DN42
J 2
(-5035 3385);
DISPLAY 0.617021 (-5035 3385);
PAINT ORANGE (-5035 3385);
FORCEPROP 2 LASTPIN (-5025 3325) $PN DL42
J 2
(-5035 3335);
DISPLAY 0.617021 (-5035 3335);
PAINT ORANGE (-5035 3335);
FORCEPROP 2 LASTPIN (-5025 3275) $PN DT39
J 2
(-5035 3285);
DISPLAY 0.617021 (-5035 3285);
PAINT ORANGE (-5035 3285);
FORCEPROP 2 LASTPIN (-5025 3225) $PN DP39
J 2
(-5035 3235);
DISPLAY 0.617021 (-5035 3235);
PAINT ORANGE (-5035 3235);
FORCEPROP 2 LASTPIN (-5025 3175) $PN DW42
J 2
(-5035 3185);
DISPLAY 0.617021 (-5035 3185);
PAINT ORANGE (-5035 3185);
FORCEPROP 2 LASTPIN (-5025 3125) $PN DU42
J 2
(-5035 3135);
DISPLAY 0.617021 (-5035 3135);
PAINT ORANGE (-5035 3135);
FORCEPROP 2 LASTPIN (-5025 3075) $PN EE72
J 2
(-5035 3085);
DISPLAY 0.617021 (-5035 3085);
PAINT ORANGE (-5035 3085);
FORCEPROP 2 LASTPIN (-5025 3025) $PN EA72
J 2
(-5035 3035);
DISPLAY 0.617021 (-5035 3035);
PAINT ORANGE (-5035 3035);
FORCEPROP 2 LASTPIN (-5025 2975) $PN EB75
J 2
(-5035 2985);
DISPLAY 0.617021 (-5035 2985);
PAINT ORANGE (-5035 2985);
FORCEPROP 2 LASTPIN (-5025 2925) $PN EA74
J 2
(-5035 2935);
DISPLAY 0.617021 (-5035 2935);
PAINT ORANGE (-5035 2935);
FORCEPROP 2 LASTPIN (-5025 2875) $PN ED71
J 2
(-5035 2885);
DISPLAY 0.617021 (-5035 2885);
PAINT ORANGE (-5035 2885);
FORCEPROP 2 LASTPIN (-5025 2825) $PN EB71
J 2
(-5035 2835);
DISPLAY 0.617021 (-5035 2835);
PAINT ORANGE (-5035 2835);
FORCEPROP 2 LASTPIN (-5025 2775) $PN EE74
J 2
(-5035 2785);
DISPLAY 0.617021 (-5035 2785);
PAINT ORANGE (-5035 2785);
FORCEPROP 2 LASTPIN (-5025 2725) $PN ED75
J 2
(-5035 2735);
DISPLAY 0.617021 (-5035 2735);
PAINT ORANGE (-5035 2735);
FORCEPROP 2 LASTPIN (-5025 2675) $PN EC78
J 2
(-5035 2685);
DISPLAY 0.617021 (-5035 2685);
PAINT ORANGE (-5035 2685);
FORCEPROP 2 LASTPIN (-5025 2625) $PN DW78
J 2
(-5035 2635);
DISPLAY 0.617021 (-5035 2635);
PAINT ORANGE (-5035 2635);
FORCEPROP 2 LASTPIN (-5025 2575) $PN EB81
J 2
(-5035 2585);
DISPLAY 0.617021 (-5035 2585);
PAINT ORANGE (-5035 2585);
FORCEPROP 2 LASTPIN (-5025 2525) $PN DY81
J 2
(-5035 2535);
DISPLAY 0.617021 (-5035 2535);
PAINT ORANGE (-5035 2535);
FORCEPROP 2 LASTPIN (-5025 2475) $PN EB77
J 2
(-5035 2485);
DISPLAY 0.617021 (-5035 2485);
PAINT ORANGE (-5035 2485);
FORCEPROP 2 LASTPIN (-5025 2425) $PN DY77
J 2
(-5035 2435);
DISPLAY 0.617021 (-5035 2435);
PAINT ORANGE (-5035 2435);
FORCEPROP 2 LASTPIN (-5025 2375) $PN EC80
J 2
(-5035 2385);
DISPLAY 0.617021 (-5035 2385);
PAINT ORANGE (-5035 2385);
FORCEPROP 2 LASTPIN (-5025 2325) $PN DW80
J 2
(-5035 2335);
DISPLAY 0.617021 (-5035 2335);
PAINT ORANGE (-5035 2335);
FORCEPROP 2 LASTPIN (-5025 2275) $PN DE82
J 2
(-5035 2285);
DISPLAY 0.617021 (-5035 2285);
PAINT ORANGE (-5035 2285);
FORCEPROP 2 LASTPIN (-5025 2225) $PN DC82
J 2
(-5035 2235);
DISPLAY 0.617021 (-5035 2235);
PAINT ORANGE (-5035 2235);
FORCEPROP 2 LASTPIN (-5025 2175) $PN CW80
J 2
(-5035 2185);
DISPLAY 0.617021 (-5035 2185);
PAINT ORANGE (-5035 2185);
FORCEPROP 2 LASTPIN (-5025 2125) $PN CY79
J 2
(-5035 2135);
DISPLAY 0.617021 (-5035 2135);
PAINT ORANGE (-5035 2135);
FORCEPROP 2 LASTPIN (-5025 2075) $PN DF81
J 2
(-5035 2085);
DISPLAY 0.617021 (-5035 2085);
PAINT ORANGE (-5035 2085);
FORCEPROP 2 LASTPIN (-5025 2025) $PN DE80
J 2
(-5035 2035);
DISPLAY 0.617021 (-5035 2035);
PAINT ORANGE (-5035 2035);
FORCEPROP 2 LASTPIN (-5025 1975) $PN CY81
J 2
(-5035 1985);
DISPLAY 0.617021 (-5035 1985);
PAINT ORANGE (-5035 1985);
FORCEPROP 2 LASTPIN (-5025 1925) $PN DB79
J 2
(-5035 1935);
DISPLAY 0.617021 (-5035 1935);
PAINT ORANGE (-5035 1935);
FORCEPROP 2 LASTPIN (-5025 1875) $PN CN82
J 2
(-5035 1885);
DISPLAY 0.617021 (-5035 1885);
PAINT ORANGE (-5035 1885);
FORCEPROP 2 LASTPIN (-5025 1825) $PN CR80
J 2
(-5035 1835);
DISPLAY 0.617021 (-5035 1835);
PAINT ORANGE (-5035 1835);
FORCEPROP 2 LASTPIN (-5025 1775) $PN CJ80
J 2
(-5035 1785);
DISPLAY 0.617021 (-5035 1785);
PAINT ORANGE (-5035 1785);
FORCEPROP 2 LASTPIN (-5025 1725) $PN CK79
J 2
(-5035 1735);
DISPLAY 0.617021 (-5035 1735);
PAINT ORANGE (-5035 1735);
FORCEPROP 2 LASTPIN (-5025 1675) $PN CR82
J 2
(-5035 1685);
DISPLAY 0.617021 (-5035 1685);
PAINT ORANGE (-5035 1685);
FORCEPROP 2 LASTPIN (-5025 1625) $PN CT81
J 2
(-5035 1635);
DISPLAY 0.617021 (-5035 1635);
PAINT ORANGE (-5035 1635);
FORCEPROP 2 LASTPIN (-5025 1575) $PN CK81
J 2
(-5035 1585);
DISPLAY 0.617021 (-5035 1585);
PAINT ORANGE (-5035 1585);
FORCEPROP 2 LASTPIN (-5025 1525) $PN CM79
J 2
(-5035 1535);
DISPLAY 0.617021 (-5035 1535);
PAINT ORANGE (-5035 1535);
FORCEPROP 2 LASTPIN (-3325 1325) $PN DN46
J 0
(-3315 1335);
DISPLAY 0.617021 (-3315 1335);
PAINT ORANGE (-3315 1335);
FORCEPROP 2 LASTPIN (-3325 1275) $PN DT45
J 0
(-3315 1285);
DISPLAY 0.617021 (-3315 1285);
PAINT ORANGE (-3315 1285);
FORCEPROP 2 LASTPIN (-3325 1225) $PN DM49
J 0
(-3315 1235);
DISPLAY 0.617021 (-3315 1235);
PAINT ORANGE (-3315 1235);
FORCEPROP 2 LASTPIN (-3325 1175) $PN DW50
J 0
(-3315 1185);
DISPLAY 0.617021 (-3315 1185);
PAINT ORANGE (-3315 1185);
FORCEPROP 2 LASTPIN (-3325 1125) $PN DK47
J 0
(-3315 1135);
DISPLAY 0.617021 (-3315 1135);
PAINT ORANGE (-3315 1135);
FORCEPROP 2 LASTPIN (-3325 1075) $PN DR46
J 0
(-3315 1085);
DISPLAY 0.617021 (-3315 1085);
PAINT ORANGE (-3315 1085);
FORCEPROP 2 LASTPIN (-3325 1025) $PN DN50
J 0
(-3315 1035);
DISPLAY 0.617021 (-3315 1035);
PAINT ORANGE (-3315 1035);
FORCEPROP 2 LASTPIN (-3325 975) $PN DV51
J 0
(-3315 985);
DISPLAY 0.617021 (-3315 985);
PAINT ORANGE (-3315 985);
FORCEPROP 2 LASTPIN (-5025 975) $PN DR56
J 2
(-5035 985);
DISPLAY 0.617021 (-5035 985);
PAINT ORANGE (-5035 985);
FORCEPROP 2 LASTPIN (-5025 925) $PN DN56
J 2
(-5035 935);
DISPLAY 0.617021 (-5035 935);
PAINT ORANGE (-5035 935);
FORCEPROP 2 LASTPIN (-5025 875) $PN DT53
J 2
(-5035 885);
DISPLAY 0.617021 (-5035 885);
PAINT ORANGE (-5035 885);
FORCEPROP 2 LASTPIN (-5025 825) $PN DN54
J 2
(-5035 835);
DISPLAY 0.617021 (-5035 835);
PAINT ORANGE (-5035 835);
FORCEPROP 2 LASTPIN (-5025 775) $PN DT57
J 2
(-5035 785);
DISPLAY 0.617021 (-5035 785);
PAINT ORANGE (-5035 785);
FORCEPROP 2 LASTPIN (-5025 725) $PN DM57
J 2
(-5035 735);
DISPLAY 0.617021 (-5035 735);
PAINT ORANGE (-5035 735);
FORCEPROP 2 LASTPIN (-5025 675) $PN DR54
J 2
(-5035 685);
DISPLAY 0.617021 (-5035 685);
PAINT ORANGE (-5035 685);
FORCEPROP 2 LASTPIN (-5025 625) $PN DM55
J 2
(-5035 635);
DISPLAY 0.617021 (-5035 635);
PAINT ORANGE (-5035 635);
FORCEPROP 2 LASTPIN (-3325 1825) $PN DR64
J 0
(-3315 1835);
DISPLAY 0.617021 (-3315 1835);
PAINT ORANGE (-3315 1835);
FORCEPROP 2 LASTPIN (-3325 1775) $PN DL64
J 0
(-3315 1785);
DISPLAY 0.617021 (-3315 1785);
PAINT ORANGE (-3315 1785);
FORCEPROP 2 LASTPIN (-3325 1725) $PN DN64
J 0
(-3315 1735);
DISPLAY 0.617021 (-3315 1735);
PAINT ORANGE (-3315 1735);
FORCEPROP 2 LASTPIN (-3325 1675) $PN DM63
J 0
(-3315 1685);
DISPLAY 0.617021 (-3315 1685);
PAINT ORANGE (-3315 1685);
FORCEPROP 2 LASTPIN (-5025 525) $PN DT47
J 2
(-5035 535);
DISPLAY 0.617021 (-5035 535);
PAINT ORANGE (-5035 535);
FORCEPROP 2 LASTPIN (-3325 875) $PN DM61
J 0
(-3315 885);
DISPLAY 0.617021 (-3315 885);
PAINT ORANGE (-3315 885);
FORCEPROP 2 LASTPIN (-3325 825) $PN DJ62
J 0
(-3315 835);
DISPLAY 0.617021 (-3315 835);
PAINT ORANGE (-3315 835);
FORCEPROP 2 LASTPIN (-3325 775) $PN DV55
J 0
(-3315 785);
DISPLAY 0.617021 (-3315 785);
PAINT ORANGE (-3315 785);
FORCEPROP 2 LASTPIN (-3325 725) $PN DM53
J 0
(-3315 735);
DISPLAY 0.617021 (-3315 735);
PAINT ORANGE (-3315 735);
FORCEPROP 2 LASTPIN (-3325 575) $PN DT61
J 0
(-3315 585);
DISPLAY 0.617021 (-3315 585);
PAINT ORANGE (-3315 585);
FORCEPROP 2 LASTPIN (-3325 625) $PN DR62
J 0
(-3315 635);
DISPLAY 0.617021 (-3315 635);
PAINT ORANGE (-3315 635);
FORCEPROP 1 LAST PACK_TYPE BGA1
J 0
(-4975 4975);
PAINT SKYBLUE (-4975 4975);
DISPLAY INVISIBLE (-4975 4975);
FORCEPROP 2 LAST SEC_TYPE BGA1
J 0
(-4975 4975);
DISPLAY 1.021277 (-4975 4975);
PAINT ORANGE (-4975 4975);
DISPLAY INVISIBLE (-4975 4975);
FORCEPROP 2 LAST CDS_LIB chpset_lib
J 0
(-4175 2575);
PAINT ORANGE (-4175 2575);
DISPLAY INVISIBLE (-4175 2575);
FORCEPROP 2 LAST SEC 7
J 0
(-4975 4975);
DISPLAY 0.680851 (-4975 4975);
PAINT MONO (-4975 4975);
DISPLAY INVISIBLE (-4975 4975);
FORCEPROP 2 LAST CDS_LOCATION U2D1
J 0
(-4975 4925);
DISPLAY 0.617021 (-4975 4925);
PAINT AQUA (-4975 4925);
DISPLAY INVISIBLE (-4975 4925);
FORCEPROP 1 LAST PATH I172
J 0
(-4175 4875);
PAINT GREEN (-4175 4875);
DISPLAY INVISIBLE (-4175 4875);
FORCEADD TAP..6
(-5575 1325);
FORCEPROP 3 LASTPIN (-5525 1325) SIG_NAME M_L_ECC<5>
J 0
(-5515 1335);
DISPLAY 0.659574 (-5515 1335);
PAINT MONO (-5515 1335);
DISPLAY INVISIBLE (-5515 1335);
FORCEPROP 1 LASTPIN (-5525 1325) BN 5
J 0
(-5577 1333);
DISPLAY 0.617021 (-5577 1333);
PAINT GREEN (-5577 1333);
FORCEPROP 2 LAST CDS_LIB mstr_standard
J 0
(-5575 1325);
PAINT MONO (-5575 1325);
DISPLAY INVISIBLE (-5575 1325);
FORCEPROP 1 LAST BODY_TYPE PLUMBING
J 0
(-5575 1275);
DISPLAY 1.595745 (-5575 1275);
PAINT GREEN (-5575 1275);
DISPLAY INVISIBLE (-5575 1275);
FORCEPROP 1 LAST HDL_TAP TRUE
J 0
(-5250 1200);
DISPLAY 1.595745 (-5250 1200);
PAINT GREEN (-5250 1200);
DISPLAY INVISIBLE (-5250 1200);
FORCEPROP 1 LAST PATH I18
J 0
(-5577 1325);
DISPLAY 0.872340 (-5577 1325);
PAINT GREEN (-5577 1325);
DISPLAY INVISIBLE (-5577 1325);
FORCEADD TAP..6
(-5575 1375);
FORCEPROP 3 LASTPIN (-5525 1375) SIG_NAME M_L_ECC<6>
J 0
(-5515 1385);
DISPLAY 0.659574 (-5515 1385);
PAINT MONO (-5515 1385);
DISPLAY INVISIBLE (-5515 1385);
FORCEPROP 1 LASTPIN (-5525 1375) BN 6
J 0
(-5577 1383);
DISPLAY 0.617021 (-5577 1383);
PAINT GREEN (-5577 1383);
FORCEPROP 2 LAST CDS_LIB mstr_standard
J 0
(-5575 1375);
PAINT MONO (-5575 1375);
DISPLAY INVISIBLE (-5575 1375);
FORCEPROP 1 LAST BODY_TYPE PLUMBING
J 0
(-5575 1325);
DISPLAY 1.595745 (-5575 1325);
PAINT GREEN (-5575 1325);
DISPLAY INVISIBLE (-5575 1325);
FORCEPROP 1 LAST HDL_TAP TRUE
J 0
(-5250 1250);
DISPLAY 1.595745 (-5250 1250);
PAINT GREEN (-5250 1250);
DISPLAY INVISIBLE (-5250 1250);
FORCEPROP 1 LAST PATH I19
J 0
(-5577 1375);
DISPLAY 0.872340 (-5577 1375);
PAINT GREEN (-5577 1375);
DISPLAY INVISIBLE (-5577 1375);
FORCEADD OFFPAGE..5
(-6425 825);
FORCEPROP 2 LAST $XR0 85 
J 0
(-6679 825);
DISPLAY 0.638298 (-6679 825);
PAINT MONO (-6679 825);
FORCEPROP 2 LAST $XR1 86 
J 0
(-6769 825);
DISPLAY 0.638298 (-6769 825);
PAINT MONO (-6769 825);
FORCEPROP 2 LAST CDS_LIB mstr_standard
J 0
(-6425 825);
PAINT MONO (-6425 825);
DISPLAY INVISIBLE (-6425 825);
FORCEPROP 1 LAST OFFPAGE TRUE
J 0
(-6100 700);
DISPLAY 1.170213 (-6100 700);
PAINT GREEN (-6100 700);
DISPLAY INVISIBLE (-6100 700);
FORCEPROP 1 LAST COMMENT_BODY TRUE
J 0
(-6325 750);
DISPLAY 1.170213 (-6325 750);
PAINT GREEN (-6325 750);
DISPLAY INVISIBLE (-6325 750);
FORCEPROP 2 LAST PATH I2
J 0
(-6375 900);
DISPLAY 1.021277 (-6375 900);
PAINT ORANGE (-6375 900);
DISPLAY INVISIBLE (-6375 900);
FORCEADD TAP..6
(-5575 1425);
FORCEPROP 3 LASTPIN (-5525 1425) SIG_NAME M_L_ECC<7>
J 0
(-5515 1435);
DISPLAY 0.659574 (-5515 1435);
PAINT MONO (-5515 1435);
DISPLAY INVISIBLE (-5515 1435);
FORCEPROP 1 LASTPIN (-5525 1425) BN 7
J 0
(-5577 1433);
DISPLAY 0.617021 (-5577 1433);
PAINT GREEN (-5577 1433);
FORCEPROP 2 LAST CDS_LIB mstr_standard
J 0
(-5575 1425);
PAINT MONO (-5575 1425);
DISPLAY INVISIBLE (-5575 1425);
FORCEPROP 1 LAST BODY_TYPE PLUMBING
J 0
(-5575 1375);
DISPLAY 1.595745 (-5575 1375);
PAINT GREEN (-5575 1375);
DISPLAY INVISIBLE (-5575 1375);
FORCEPROP 1 LAST HDL_TAP TRUE
J 0
(-5250 1300);
DISPLAY 1.595745 (-5250 1300);
PAINT GREEN (-5250 1300);
DISPLAY INVISIBLE (-5250 1300);
FORCEPROP 1 LAST PATH I20
J 0
(-5577 1425);
DISPLAY 0.872340 (-5577 1425);
PAINT GREEN (-5577 1425);
DISPLAY INVISIBLE (-5577 1425);
FORCEADD TAP..6
(-5575 1525);
FORCEPROP 3 LASTPIN (-5525 1525) SIG_NAME M_L_DQ<0>
J 0
(-5515 1535);
DISPLAY 0.659574 (-5515 1535);
PAINT MONO (-5515 1535);
DISPLAY INVISIBLE (-5515 1535);
FORCEPROP 1 LASTPIN (-5525 1525) BN 0
J 0
(-5577 1533);
DISPLAY 0.617021 (-5577 1533);
PAINT GREEN (-5577 1533);
FORCEPROP 2 LAST CDS_LIB mstr_standard
J 0
(-5575 1525);
PAINT MONO (-5575 1525);
DISPLAY INVISIBLE (-5575 1525);
FORCEPROP 1 LAST BODY_TYPE PLUMBING
J 0
(-5575 1475);
DISPLAY 1.595745 (-5575 1475);
PAINT GREEN (-5575 1475);
DISPLAY INVISIBLE (-5575 1475);
FORCEPROP 1 LAST HDL_TAP TRUE
J 0
(-5250 1400);
DISPLAY 1.595745 (-5250 1400);
PAINT GREEN (-5250 1400);
DISPLAY INVISIBLE (-5250 1400);
FORCEPROP 1 LAST PATH I21
J 0
(-5577 1525);
DISPLAY 0.872340 (-5577 1525);
PAINT GREEN (-5577 1525);
DISPLAY INVISIBLE (-5577 1525);
FORCEADD TAP..6
(-5575 1575);
FORCEPROP 3 LASTPIN (-5525 1575) SIG_NAME M_L_DQ<1>
J 0
(-5515 1585);
DISPLAY 0.659574 (-5515 1585);
PAINT MONO (-5515 1585);
DISPLAY INVISIBLE (-5515 1585);
FORCEPROP 1 LASTPIN (-5525 1575) BN 1
J 0
(-5577 1583);
DISPLAY 0.617021 (-5577 1583);
PAINT GREEN (-5577 1583);
FORCEPROP 2 LAST CDS_LIB mstr_standard
J 0
(-5575 1575);
PAINT MONO (-5575 1575);
DISPLAY INVISIBLE (-5575 1575);
FORCEPROP 1 LAST BODY_TYPE PLUMBING
J 0
(-5575 1525);
DISPLAY 1.595745 (-5575 1525);
PAINT GREEN (-5575 1525);
DISPLAY INVISIBLE (-5575 1525);
FORCEPROP 1 LAST HDL_TAP TRUE
J 0
(-5250 1450);
DISPLAY 1.595745 (-5250 1450);
PAINT GREEN (-5250 1450);
DISPLAY INVISIBLE (-5250 1450);
FORCEPROP 1 LAST PATH I22
J 0
(-5577 1575);
DISPLAY 0.872340 (-5577 1575);
PAINT GREEN (-5577 1575);
DISPLAY INVISIBLE (-5577 1575);
FORCEADD TAP..6
(-5575 1625);
FORCEPROP 3 LASTPIN (-5525 1625) SIG_NAME M_L_DQ<2>
J 0
(-5515 1635);
DISPLAY 0.659574 (-5515 1635);
PAINT MONO (-5515 1635);
DISPLAY INVISIBLE (-5515 1635);
FORCEPROP 1 LASTPIN (-5525 1625) BN 2
J 0
(-5577 1633);
DISPLAY 0.617021 (-5577 1633);
PAINT GREEN (-5577 1633);
FORCEPROP 2 LAST CDS_LIB mstr_standard
J 0
(-5575 1625);
PAINT MONO (-5575 1625);
DISPLAY INVISIBLE (-5575 1625);
FORCEPROP 1 LAST BODY_TYPE PLUMBING
J 0
(-5575 1575);
DISPLAY 1.595745 (-5575 1575);
PAINT GREEN (-5575 1575);
DISPLAY INVISIBLE (-5575 1575);
FORCEPROP 1 LAST HDL_TAP TRUE
J 0
(-5250 1500);
DISPLAY 1.595745 (-5250 1500);
PAINT GREEN (-5250 1500);
DISPLAY INVISIBLE (-5250 1500);
FORCEPROP 1 LAST PATH I23
J 0
(-5577 1625);
DISPLAY 0.872340 (-5577 1625);
PAINT GREEN (-5577 1625);
DISPLAY INVISIBLE (-5577 1625);
FORCEADD TAP..6
(-5575 1675);
FORCEPROP 3 LASTPIN (-5525 1675) SIG_NAME M_L_DQ<3>
J 0
(-5515 1685);
DISPLAY 0.659574 (-5515 1685);
PAINT MONO (-5515 1685);
DISPLAY INVISIBLE (-5515 1685);
FORCEPROP 1 LASTPIN (-5525 1675) BN 3
J 0
(-5577 1683);
DISPLAY 0.617021 (-5577 1683);
PAINT GREEN (-5577 1683);
FORCEPROP 2 LAST CDS_LIB mstr_standard
J 0
(-5575 1675);
PAINT MONO (-5575 1675);
DISPLAY INVISIBLE (-5575 1675);
FORCEPROP 1 LAST BODY_TYPE PLUMBING
J 0
(-5575 1625);
DISPLAY 1.595745 (-5575 1625);
PAINT GREEN (-5575 1625);
DISPLAY INVISIBLE (-5575 1625);
FORCEPROP 1 LAST HDL_TAP TRUE
J 0
(-5250 1550);
DISPLAY 1.595745 (-5250 1550);
PAINT GREEN (-5250 1550);
DISPLAY INVISIBLE (-5250 1550);
FORCEPROP 1 LAST PATH I24
J 0
(-5577 1675);
DISPLAY 0.872340 (-5577 1675);
PAINT GREEN (-5577 1675);
DISPLAY INVISIBLE (-5577 1675);
FORCEADD TAP..6
(-5575 1725);
FORCEPROP 3 LASTPIN (-5525 1725) SIG_NAME M_L_DQ<4>
J 0
(-5515 1735);
DISPLAY 0.659574 (-5515 1735);
PAINT MONO (-5515 1735);
DISPLAY INVISIBLE (-5515 1735);
FORCEPROP 1 LASTPIN (-5525 1725) BN 4
J 0
(-5577 1733);
DISPLAY 0.617021 (-5577 1733);
PAINT GREEN (-5577 1733);
FORCEPROP 2 LAST CDS_LIB mstr_standard
J 0
(-5575 1725);
PAINT MONO (-5575 1725);
DISPLAY INVISIBLE (-5575 1725);
FORCEPROP 1 LAST BODY_TYPE PLUMBING
J 0
(-5575 1675);
DISPLAY 1.595745 (-5575 1675);
PAINT GREEN (-5575 1675);
DISPLAY INVISIBLE (-5575 1675);
FORCEPROP 1 LAST HDL_TAP TRUE
J 0
(-5250 1600);
DISPLAY 1.595745 (-5250 1600);
PAINT GREEN (-5250 1600);
DISPLAY INVISIBLE (-5250 1600);
FORCEPROP 1 LAST PATH I25
J 0
(-5577 1725);
DISPLAY 0.872340 (-5577 1725);
PAINT GREEN (-5577 1725);
DISPLAY INVISIBLE (-5577 1725);
FORCEADD TAP..6
(-5575 1775);
FORCEPROP 3 LASTPIN (-5525 1775) SIG_NAME M_L_DQ<5>
J 0
(-5515 1785);
DISPLAY 0.659574 (-5515 1785);
PAINT MONO (-5515 1785);
DISPLAY INVISIBLE (-5515 1785);
FORCEPROP 1 LASTPIN (-5525 1775) BN 5
J 0
(-5577 1783);
DISPLAY 0.617021 (-5577 1783);
PAINT GREEN (-5577 1783);
FORCEPROP 2 LAST CDS_LIB mstr_standard
J 0
(-5575 1775);
PAINT MONO (-5575 1775);
DISPLAY INVISIBLE (-5575 1775);
FORCEPROP 1 LAST BODY_TYPE PLUMBING
J 0
(-5575 1725);
DISPLAY 1.595745 (-5575 1725);
PAINT GREEN (-5575 1725);
DISPLAY INVISIBLE (-5575 1725);
FORCEPROP 1 LAST HDL_TAP TRUE
J 0
(-5250 1650);
DISPLAY 1.595745 (-5250 1650);
PAINT GREEN (-5250 1650);
DISPLAY INVISIBLE (-5250 1650);
FORCEPROP 1 LAST PATH I26
J 0
(-5577 1775);
DISPLAY 0.872340 (-5577 1775);
PAINT GREEN (-5577 1775);
DISPLAY INVISIBLE (-5577 1775);
FORCEADD TAP..6
(-5575 1825);
FORCEPROP 3 LASTPIN (-5525 1825) SIG_NAME M_L_DQ<6>
J 0
(-5515 1835);
DISPLAY 0.659574 (-5515 1835);
PAINT MONO (-5515 1835);
DISPLAY INVISIBLE (-5515 1835);
FORCEPROP 1 LASTPIN (-5525 1825) BN 6
J 0
(-5577 1833);
DISPLAY 0.617021 (-5577 1833);
PAINT GREEN (-5577 1833);
FORCEPROP 2 LAST CDS_LIB mstr_standard
J 0
(-5575 1825);
PAINT MONO (-5575 1825);
DISPLAY INVISIBLE (-5575 1825);
FORCEPROP 1 LAST BODY_TYPE PLUMBING
J 0
(-5575 1775);
DISPLAY 1.595745 (-5575 1775);
PAINT GREEN (-5575 1775);
DISPLAY INVISIBLE (-5575 1775);
FORCEPROP 1 LAST HDL_TAP TRUE
J 0
(-5250 1700);
DISPLAY 1.595745 (-5250 1700);
PAINT GREEN (-5250 1700);
DISPLAY INVISIBLE (-5250 1700);
FORCEPROP 1 LAST PATH I27
J 0
(-5577 1825);
DISPLAY 0.872340 (-5577 1825);
PAINT GREEN (-5577 1825);
DISPLAY INVISIBLE (-5577 1825);
FORCEADD TAP..6
(-5575 1925);
FORCEPROP 3 LASTPIN (-5525 1925) SIG_NAME M_L_DQ<8>
J 0
(-5515 1935);
DISPLAY 0.659574 (-5515 1935);
PAINT MONO (-5515 1935);
DISPLAY INVISIBLE (-5515 1935);
FORCEPROP 1 LASTPIN (-5525 1925) BN 8
J 0
(-5577 1933);
DISPLAY 0.617021 (-5577 1933);
PAINT GREEN (-5577 1933);
FORCEPROP 2 LAST CDS_LIB mstr_standard
J 0
(-5575 1925);
PAINT MONO (-5575 1925);
DISPLAY INVISIBLE (-5575 1925);
FORCEPROP 1 LAST BODY_TYPE PLUMBING
J 0
(-5575 1875);
DISPLAY 1.595745 (-5575 1875);
PAINT GREEN (-5575 1875);
DISPLAY INVISIBLE (-5575 1875);
FORCEPROP 1 LAST HDL_TAP TRUE
J 0
(-5250 1800);
DISPLAY 1.595745 (-5250 1800);
PAINT GREEN (-5250 1800);
DISPLAY INVISIBLE (-5250 1800);
FORCEPROP 1 LAST PATH I28
J 0
(-5577 1925);
DISPLAY 0.872340 (-5577 1925);
PAINT GREEN (-5577 1925);
DISPLAY INVISIBLE (-5577 1925);
FORCEADD TAP..6
(-5575 1875);
FORCEPROP 3 LASTPIN (-5525 1875) SIG_NAME M_L_DQ<7>
J 0
(-5515 1885);
DISPLAY 0.659574 (-5515 1885);
PAINT MONO (-5515 1885);
DISPLAY INVISIBLE (-5515 1885);
FORCEPROP 1 LASTPIN (-5525 1875) BN 7
J 0
(-5577 1883);
DISPLAY 0.617021 (-5577 1883);
PAINT GREEN (-5577 1883);
FORCEPROP 2 LAST CDS_LIB mstr_standard
J 0
(-5575 1875);
PAINT MONO (-5575 1875);
DISPLAY INVISIBLE (-5575 1875);
FORCEPROP 1 LAST BODY_TYPE PLUMBING
J 0
(-5575 1825);
DISPLAY 1.595745 (-5575 1825);
PAINT GREEN (-5575 1825);
DISPLAY INVISIBLE (-5575 1825);
FORCEPROP 1 LAST HDL_TAP TRUE
J 0
(-5250 1750);
DISPLAY 1.595745 (-5250 1750);
PAINT GREEN (-5250 1750);
DISPLAY INVISIBLE (-5250 1750);
FORCEPROP 1 LAST PATH I29
J 0
(-5577 1875);
DISPLAY 0.872340 (-5577 1875);
PAINT GREEN (-5577 1875);
DISPLAY INVISIBLE (-5577 1875);
FORCEADD OFFPAGE..5
(-6425 1025);
FORCEPROP 2 LAST $XR0 85 
J 0
(-6679 1025);
DISPLAY 0.638298 (-6679 1025);
PAINT MONO (-6679 1025);
FORCEPROP 2 LAST $XR1 86 
J 0
(-6769 1025);
DISPLAY 0.638298 (-6769 1025);
PAINT MONO (-6769 1025);
FORCEPROP 2 LAST CDS_LIB mstr_standard
J 0
(-6425 1025);
PAINT MONO (-6425 1025);
DISPLAY INVISIBLE (-6425 1025);
FORCEPROP 1 LAST OFFPAGE TRUE
J 0
(-6100 900);
DISPLAY 1.170213 (-6100 900);
PAINT GREEN (-6100 900);
DISPLAY INVISIBLE (-6100 900);
FORCEPROP 1 LAST COMMENT_BODY TRUE
J 0
(-6325 950);
DISPLAY 1.170213 (-6325 950);
PAINT GREEN (-6325 950);
DISPLAY INVISIBLE (-6325 950);
FORCEPROP 2 LAST PATH I3
J 0
(-6375 1100);
DISPLAY 1.021277 (-6375 1100);
PAINT ORANGE (-6375 1100);
DISPLAY INVISIBLE (-6375 1100);
FORCEADD TAP..6
(-5575 1975);
FORCEPROP 3 LASTPIN (-5525 1975) SIG_NAME M_L_DQ<9>
J 0
(-5515 1985);
DISPLAY 0.659574 (-5515 1985);
PAINT MONO (-5515 1985);
DISPLAY INVISIBLE (-5515 1985);
FORCEPROP 1 LASTPIN (-5525 1975) BN 9
J 0
(-5577 1983);
DISPLAY 0.617021 (-5577 1983);
PAINT GREEN (-5577 1983);
FORCEPROP 2 LAST CDS_LIB mstr_standard
J 0
(-5575 1975);
PAINT MONO (-5575 1975);
DISPLAY INVISIBLE (-5575 1975);
FORCEPROP 1 LAST BODY_TYPE PLUMBING
J 0
(-5575 1925);
DISPLAY 1.595745 (-5575 1925);
PAINT GREEN (-5575 1925);
DISPLAY INVISIBLE (-5575 1925);
FORCEPROP 1 LAST HDL_TAP TRUE
J 0
(-5250 1850);
DISPLAY 1.595745 (-5250 1850);
PAINT GREEN (-5250 1850);
DISPLAY INVISIBLE (-5250 1850);
FORCEPROP 1 LAST PATH I31
J 0
(-5577 1975);
DISPLAY 0.872340 (-5577 1975);
PAINT GREEN (-5577 1975);
DISPLAY INVISIBLE (-5577 1975);
FORCEADD TAP..6
(-5575 2025);
FORCEPROP 3 LASTPIN (-5525 2025) SIG_NAME M_L_DQ<10>
J 0
(-5515 2035);
DISPLAY 0.659574 (-5515 2035);
PAINT MONO (-5515 2035);
DISPLAY INVISIBLE (-5515 2035);
FORCEPROP 1 LASTPIN (-5525 2025) BN 10
J 0
(-5577 2033);
DISPLAY 0.617021 (-5577 2033);
PAINT GREEN (-5577 2033);
FORCEPROP 2 LAST CDS_LIB mstr_standard
J 0
(-5575 2025);
PAINT MONO (-5575 2025);
DISPLAY INVISIBLE (-5575 2025);
FORCEPROP 1 LAST BODY_TYPE PLUMBING
J 0
(-5575 1975);
DISPLAY 1.595745 (-5575 1975);
PAINT GREEN (-5575 1975);
DISPLAY INVISIBLE (-5575 1975);
FORCEPROP 1 LAST HDL_TAP TRUE
J 0
(-5250 1900);
DISPLAY 1.595745 (-5250 1900);
PAINT GREEN (-5250 1900);
DISPLAY INVISIBLE (-5250 1900);
FORCEPROP 1 LAST PATH I32
J 0
(-5577 2025);
DISPLAY 0.872340 (-5577 2025);
PAINT GREEN (-5577 2025);
DISPLAY INVISIBLE (-5577 2025);
FORCEADD TAP..6
(-5575 2075);
FORCEPROP 3 LASTPIN (-5525 2075) SIG_NAME M_L_DQ<11>
J 0
(-5515 2085);
DISPLAY 0.659574 (-5515 2085);
PAINT MONO (-5515 2085);
DISPLAY INVISIBLE (-5515 2085);
FORCEPROP 1 LASTPIN (-5525 2075) BN 11
J 0
(-5577 2083);
DISPLAY 0.617021 (-5577 2083);
PAINT GREEN (-5577 2083);
FORCEPROP 2 LAST CDS_LIB mstr_standard
J 0
(-5575 2075);
PAINT MONO (-5575 2075);
DISPLAY INVISIBLE (-5575 2075);
FORCEPROP 1 LAST BODY_TYPE PLUMBING
J 0
(-5575 2025);
DISPLAY 1.595745 (-5575 2025);
PAINT GREEN (-5575 2025);
DISPLAY INVISIBLE (-5575 2025);
FORCEPROP 1 LAST HDL_TAP TRUE
J 0
(-5250 1950);
DISPLAY 1.595745 (-5250 1950);
PAINT GREEN (-5250 1950);
DISPLAY INVISIBLE (-5250 1950);
FORCEPROP 1 LAST PATH I33
J 0
(-5577 2075);
DISPLAY 0.872340 (-5577 2075);
PAINT GREEN (-5577 2075);
DISPLAY INVISIBLE (-5577 2075);
FORCEADD TAP..6
(-5575 2125);
FORCEPROP 3 LASTPIN (-5525 2125) SIG_NAME M_L_DQ<12>
J 0
(-5515 2135);
DISPLAY 0.659574 (-5515 2135);
PAINT MONO (-5515 2135);
DISPLAY INVISIBLE (-5515 2135);
FORCEPROP 1 LASTPIN (-5525 2125) BN 12
J 0
(-5577 2133);
DISPLAY 0.617021 (-5577 2133);
PAINT GREEN (-5577 2133);
FORCEPROP 2 LAST CDS_LIB mstr_standard
J 0
(-5575 2125);
PAINT MONO (-5575 2125);
DISPLAY INVISIBLE (-5575 2125);
FORCEPROP 1 LAST BODY_TYPE PLUMBING
J 0
(-5575 2075);
DISPLAY 1.595745 (-5575 2075);
PAINT GREEN (-5575 2075);
DISPLAY INVISIBLE (-5575 2075);
FORCEPROP 1 LAST HDL_TAP TRUE
J 0
(-5250 2000);
DISPLAY 1.595745 (-5250 2000);
PAINT GREEN (-5250 2000);
DISPLAY INVISIBLE (-5250 2000);
FORCEPROP 1 LAST PATH I34
J 0
(-5577 2125);
DISPLAY 0.872340 (-5577 2125);
PAINT GREEN (-5577 2125);
DISPLAY INVISIBLE (-5577 2125);
FORCEADD TAP..6
(-5575 2175);
FORCEPROP 3 LASTPIN (-5525 2175) SIG_NAME M_L_DQ<13>
J 0
(-5515 2185);
DISPLAY 0.659574 (-5515 2185);
PAINT MONO (-5515 2185);
DISPLAY INVISIBLE (-5515 2185);
FORCEPROP 1 LASTPIN (-5525 2175) BN 13
J 0
(-5577 2183);
DISPLAY 0.617021 (-5577 2183);
PAINT GREEN (-5577 2183);
FORCEPROP 2 LAST CDS_LIB mstr_standard
J 0
(-5575 2175);
PAINT MONO (-5575 2175);
DISPLAY INVISIBLE (-5575 2175);
FORCEPROP 1 LAST BODY_TYPE PLUMBING
J 0
(-5575 2125);
DISPLAY 1.595745 (-5575 2125);
PAINT GREEN (-5575 2125);
DISPLAY INVISIBLE (-5575 2125);
FORCEPROP 1 LAST HDL_TAP TRUE
J 0
(-5250 2050);
DISPLAY 1.595745 (-5250 2050);
PAINT GREEN (-5250 2050);
DISPLAY INVISIBLE (-5250 2050);
FORCEPROP 1 LAST PATH I35
J 0
(-5577 2175);
DISPLAY 0.872340 (-5577 2175);
PAINT GREEN (-5577 2175);
DISPLAY INVISIBLE (-5577 2175);
FORCEADD TAP..6
(-5575 2225);
FORCEPROP 3 LASTPIN (-5525 2225) SIG_NAME M_L_DQ<14>
J 0
(-5515 2235);
DISPLAY 0.659574 (-5515 2235);
PAINT MONO (-5515 2235);
DISPLAY INVISIBLE (-5515 2235);
FORCEPROP 1 LASTPIN (-5525 2225) BN 14
J 0
(-5577 2233);
DISPLAY 0.617021 (-5577 2233);
PAINT GREEN (-5577 2233);
FORCEPROP 2 LAST CDS_LIB mstr_standard
J 0
(-5575 2225);
PAINT MONO (-5575 2225);
DISPLAY INVISIBLE (-5575 2225);
FORCEPROP 1 LAST BODY_TYPE PLUMBING
J 0
(-5575 2175);
DISPLAY 1.595745 (-5575 2175);
PAINT GREEN (-5575 2175);
DISPLAY INVISIBLE (-5575 2175);
FORCEPROP 1 LAST HDL_TAP TRUE
J 0
(-5250 2100);
DISPLAY 1.595745 (-5250 2100);
PAINT GREEN (-5250 2100);
DISPLAY INVISIBLE (-5250 2100);
FORCEPROP 1 LAST PATH I36
J 0
(-5577 2225);
DISPLAY 0.872340 (-5577 2225);
PAINT GREEN (-5577 2225);
DISPLAY INVISIBLE (-5577 2225);
FORCEADD TAP..6
(-5575 2275);
FORCEPROP 3 LASTPIN (-5525 2275) SIG_NAME M_L_DQ<15>
J 0
(-5515 2285);
DISPLAY 0.659574 (-5515 2285);
PAINT MONO (-5515 2285);
DISPLAY INVISIBLE (-5515 2285);
FORCEPROP 1 LASTPIN (-5525 2275) BN 15
J 0
(-5577 2283);
DISPLAY 0.617021 (-5577 2283);
PAINT GREEN (-5577 2283);
FORCEPROP 2 LAST CDS_LIB mstr_standard
J 0
(-5575 2275);
PAINT MONO (-5575 2275);
DISPLAY INVISIBLE (-5575 2275);
FORCEPROP 1 LAST BODY_TYPE PLUMBING
J 0
(-5575 2225);
DISPLAY 1.595745 (-5575 2225);
PAINT GREEN (-5575 2225);
DISPLAY INVISIBLE (-5575 2225);
FORCEPROP 1 LAST HDL_TAP TRUE
J 0
(-5250 2150);
DISPLAY 1.595745 (-5250 2150);
PAINT GREEN (-5250 2150);
DISPLAY INVISIBLE (-5250 2150);
FORCEPROP 1 LAST PATH I37
J 0
(-5577 2275);
DISPLAY 0.872340 (-5577 2275);
PAINT GREEN (-5577 2275);
DISPLAY INVISIBLE (-5577 2275);
FORCEADD TAP..6
(-5575 2325);
FORCEPROP 3 LASTPIN (-5525 2325) SIG_NAME M_L_DQ<16>
J 0
(-5515 2335);
DISPLAY 0.659574 (-5515 2335);
PAINT MONO (-5515 2335);
DISPLAY INVISIBLE (-5515 2335);
FORCEPROP 1 LASTPIN (-5525 2325) BN 16
J 0
(-5577 2333);
DISPLAY 0.617021 (-5577 2333);
PAINT GREEN (-5577 2333);
FORCEPROP 2 LAST CDS_LIB mstr_standard
J 0
(-5575 2325);
PAINT MONO (-5575 2325);
DISPLAY INVISIBLE (-5575 2325);
FORCEPROP 1 LAST BODY_TYPE PLUMBING
J 0
(-5575 2275);
DISPLAY 1.595745 (-5575 2275);
PAINT GREEN (-5575 2275);
DISPLAY INVISIBLE (-5575 2275);
FORCEPROP 1 LAST HDL_TAP TRUE
J 0
(-5250 2200);
DISPLAY 1.595745 (-5250 2200);
PAINT GREEN (-5250 2200);
DISPLAY INVISIBLE (-5250 2200);
FORCEPROP 1 LAST PATH I38
J 0
(-5577 2325);
DISPLAY 0.872340 (-5577 2325);
PAINT GREEN (-5577 2325);
DISPLAY INVISIBLE (-5577 2325);
FORCEADD TAP..6
(-5575 2375);
FORCEPROP 3 LASTPIN (-5525 2375) SIG_NAME M_L_DQ<17>
J 0
(-5515 2385);
DISPLAY 0.659574 (-5515 2385);
PAINT MONO (-5515 2385);
DISPLAY INVISIBLE (-5515 2385);
FORCEPROP 1 LASTPIN (-5525 2375) BN 17
J 0
(-5577 2383);
DISPLAY 0.617021 (-5577 2383);
PAINT GREEN (-5577 2383);
FORCEPROP 2 LAST CDS_LIB mstr_standard
J 0
(-5575 2375);
PAINT MONO (-5575 2375);
DISPLAY INVISIBLE (-5575 2375);
FORCEPROP 1 LAST BODY_TYPE PLUMBING
J 0
(-5575 2325);
DISPLAY 1.595745 (-5575 2325);
PAINT GREEN (-5575 2325);
DISPLAY INVISIBLE (-5575 2325);
FORCEPROP 1 LAST HDL_TAP TRUE
J 0
(-5250 2250);
DISPLAY 1.595745 (-5250 2250);
PAINT GREEN (-5250 2250);
DISPLAY INVISIBLE (-5250 2250);
FORCEPROP 1 LAST PATH I39
J 0
(-5577 2375);
DISPLAY 0.872340 (-5577 2375);
PAINT GREEN (-5577 2375);
DISPLAY INVISIBLE (-5577 2375);
FORCEADD OFFPAGE..6
(-6425 1475);
FORCEPROP 2 LAST $XR0 85 
J 0
(-6674 1475);
DISPLAY 0.638298 (-6674 1475);
PAINT MONO (-6674 1475);
FORCEPROP 2 LAST $XR1 86 
J 0
(-6764 1475);
DISPLAY 0.638298 (-6764 1475);
PAINT MONO (-6764 1475);
FORCEPROP 2 LAST CDS_LIB mstr_standard
J 0
(-6425 1475);
PAINT MONO (-6425 1475);
DISPLAY INVISIBLE (-6425 1475);
FORCEPROP 1 LAST OFFPAGE TRUE
J 0
(-6100 1350);
DISPLAY 1.170213 (-6100 1350);
PAINT GREEN (-6100 1350);
DISPLAY INVISIBLE (-6100 1350);
FORCEPROP 1 LAST COMMENT_BODY TRUE
J 0
(-6325 1400);
DISPLAY 1.170213 (-6325 1400);
PAINT GREEN (-6325 1400);
DISPLAY INVISIBLE (-6325 1400);
FORCEPROP 2 LAST PATH I4
J 0
(-6375 1550);
DISPLAY 1.021277 (-6375 1550);
PAINT ORANGE (-6375 1550);
DISPLAY INVISIBLE (-6375 1550);
FORCEADD TAP..6
(-5575 2425);
FORCEPROP 3 LASTPIN (-5525 2425) SIG_NAME M_L_DQ<18>
J 0
(-5515 2435);
DISPLAY 0.659574 (-5515 2435);
PAINT MONO (-5515 2435);
DISPLAY INVISIBLE (-5515 2435);
FORCEPROP 1 LASTPIN (-5525 2425) BN 18
J 0
(-5577 2433);
DISPLAY 0.617021 (-5577 2433);
PAINT GREEN (-5577 2433);
FORCEPROP 2 LAST CDS_LIB mstr_standard
J 0
(-5575 2425);
PAINT MONO (-5575 2425);
DISPLAY INVISIBLE (-5575 2425);
FORCEPROP 1 LAST BODY_TYPE PLUMBING
J 0
(-5575 2375);
DISPLAY 1.595745 (-5575 2375);
PAINT GREEN (-5575 2375);
DISPLAY INVISIBLE (-5575 2375);
FORCEPROP 1 LAST HDL_TAP TRUE
J 0
(-5250 2300);
DISPLAY 1.595745 (-5250 2300);
PAINT GREEN (-5250 2300);
DISPLAY INVISIBLE (-5250 2300);
FORCEPROP 1 LAST PATH I40
J 0
(-5577 2425);
DISPLAY 0.872340 (-5577 2425);
PAINT GREEN (-5577 2425);
DISPLAY INVISIBLE (-5577 2425);
FORCEADD TAP..6
(-5575 2475);
FORCEPROP 3 LASTPIN (-5525 2475) SIG_NAME M_L_DQ<19>
J 0
(-5515 2485);
DISPLAY 0.659574 (-5515 2485);
PAINT MONO (-5515 2485);
DISPLAY INVISIBLE (-5515 2485);
FORCEPROP 1 LASTPIN (-5525 2475) BN 19
J 0
(-5577 2483);
DISPLAY 0.617021 (-5577 2483);
PAINT GREEN (-5577 2483);
FORCEPROP 2 LAST CDS_LIB mstr_standard
J 0
(-5575 2475);
PAINT MONO (-5575 2475);
DISPLAY INVISIBLE (-5575 2475);
FORCEPROP 1 LAST BODY_TYPE PLUMBING
J 0
(-5575 2425);
DISPLAY 1.595745 (-5575 2425);
PAINT GREEN (-5575 2425);
DISPLAY INVISIBLE (-5575 2425);
FORCEPROP 1 LAST HDL_TAP TRUE
J 0
(-5250 2350);
DISPLAY 1.595745 (-5250 2350);
PAINT GREEN (-5250 2350);
DISPLAY INVISIBLE (-5250 2350);
FORCEPROP 1 LAST PATH I41
J 0
(-5577 2475);
DISPLAY 0.872340 (-5577 2475);
PAINT GREEN (-5577 2475);
DISPLAY INVISIBLE (-5577 2475);
FORCEADD TAP..6
(-5575 2525);
FORCEPROP 3 LASTPIN (-5525 2525) SIG_NAME M_L_DQ<20>
J 0
(-5515 2535);
DISPLAY 0.659574 (-5515 2535);
PAINT MONO (-5515 2535);
DISPLAY INVISIBLE (-5515 2535);
FORCEPROP 1 LASTPIN (-5525 2525) BN 20
J 0
(-5577 2533);
DISPLAY 0.617021 (-5577 2533);
PAINT GREEN (-5577 2533);
FORCEPROP 2 LAST CDS_LIB mstr_standard
J 0
(-5575 2525);
PAINT MONO (-5575 2525);
DISPLAY INVISIBLE (-5575 2525);
FORCEPROP 1 LAST BODY_TYPE PLUMBING
J 0
(-5575 2475);
DISPLAY 1.595745 (-5575 2475);
PAINT GREEN (-5575 2475);
DISPLAY INVISIBLE (-5575 2475);
FORCEPROP 1 LAST HDL_TAP TRUE
J 0
(-5250 2400);
DISPLAY 1.595745 (-5250 2400);
PAINT GREEN (-5250 2400);
DISPLAY INVISIBLE (-5250 2400);
FORCEPROP 1 LAST PATH I42
J 0
(-5577 2525);
DISPLAY 0.872340 (-5577 2525);
PAINT GREEN (-5577 2525);
DISPLAY INVISIBLE (-5577 2525);
FORCEADD TAP..6
(-5575 2575);
FORCEPROP 3 LASTPIN (-5525 2575) SIG_NAME M_L_DQ<21>
J 0
(-5515 2585);
DISPLAY 0.659574 (-5515 2585);
PAINT MONO (-5515 2585);
DISPLAY INVISIBLE (-5515 2585);
FORCEPROP 1 LASTPIN (-5525 2575) BN 21
J 0
(-5577 2583);
DISPLAY 0.617021 (-5577 2583);
PAINT GREEN (-5577 2583);
FORCEPROP 2 LAST CDS_LIB mstr_standard
J 0
(-5575 2575);
PAINT MONO (-5575 2575);
DISPLAY INVISIBLE (-5575 2575);
FORCEPROP 1 LAST BODY_TYPE PLUMBING
J 0
(-5575 2525);
DISPLAY 1.595745 (-5575 2525);
PAINT GREEN (-5575 2525);
DISPLAY INVISIBLE (-5575 2525);
FORCEPROP 1 LAST HDL_TAP TRUE
J 0
(-5250 2450);
DISPLAY 1.595745 (-5250 2450);
PAINT GREEN (-5250 2450);
DISPLAY INVISIBLE (-5250 2450);
FORCEPROP 1 LAST PATH I43
J 0
(-5577 2575);
DISPLAY 0.872340 (-5577 2575);
PAINT GREEN (-5577 2575);
DISPLAY INVISIBLE (-5577 2575);
FORCEADD TAP..6
(-5575 2625);
FORCEPROP 3 LASTPIN (-5525 2625) SIG_NAME M_L_DQ<22>
J 0
(-5515 2635);
DISPLAY 0.659574 (-5515 2635);
PAINT MONO (-5515 2635);
DISPLAY INVISIBLE (-5515 2635);
FORCEPROP 1 LASTPIN (-5525 2625) BN 22
J 0
(-5577 2633);
DISPLAY 0.617021 (-5577 2633);
PAINT GREEN (-5577 2633);
FORCEPROP 2 LAST CDS_LIB mstr_standard
J 0
(-5575 2625);
PAINT MONO (-5575 2625);
DISPLAY INVISIBLE (-5575 2625);
FORCEPROP 1 LAST BODY_TYPE PLUMBING
J 0
(-5575 2575);
DISPLAY 1.595745 (-5575 2575);
PAINT GREEN (-5575 2575);
DISPLAY INVISIBLE (-5575 2575);
FORCEPROP 1 LAST HDL_TAP TRUE
J 0
(-5250 2500);
DISPLAY 1.595745 (-5250 2500);
PAINT GREEN (-5250 2500);
DISPLAY INVISIBLE (-5250 2500);
FORCEPROP 1 LAST PATH I44
J 0
(-5577 2625);
DISPLAY 0.872340 (-5577 2625);
PAINT GREEN (-5577 2625);
DISPLAY INVISIBLE (-5577 2625);
FORCEADD TAP..6
(-5575 2675);
FORCEPROP 3 LASTPIN (-5525 2675) SIG_NAME M_L_DQ<23>
J 0
(-5515 2685);
DISPLAY 0.659574 (-5515 2685);
PAINT MONO (-5515 2685);
DISPLAY INVISIBLE (-5515 2685);
FORCEPROP 1 LASTPIN (-5525 2675) BN 23
J 0
(-5577 2683);
DISPLAY 0.617021 (-5577 2683);
PAINT GREEN (-5577 2683);
FORCEPROP 2 LAST CDS_LIB mstr_standard
J 0
(-5575 2675);
PAINT MONO (-5575 2675);
DISPLAY INVISIBLE (-5575 2675);
FORCEPROP 1 LAST BODY_TYPE PLUMBING
J 0
(-5575 2625);
DISPLAY 1.595745 (-5575 2625);
PAINT GREEN (-5575 2625);
DISPLAY INVISIBLE (-5575 2625);
FORCEPROP 1 LAST HDL_TAP TRUE
J 0
(-5250 2550);
DISPLAY 1.595745 (-5250 2550);
PAINT GREEN (-5250 2550);
DISPLAY INVISIBLE (-5250 2550);
FORCEPROP 1 LAST PATH I45
J 0
(-5577 2675);
DISPLAY 0.872340 (-5577 2675);
PAINT GREEN (-5577 2675);
DISPLAY INVISIBLE (-5577 2675);
FORCEADD TAP..6
(-5575 2725);
FORCEPROP 3 LASTPIN (-5525 2725) SIG_NAME M_L_DQ<24>
J 0
(-5515 2735);
DISPLAY 0.659574 (-5515 2735);
PAINT MONO (-5515 2735);
DISPLAY INVISIBLE (-5515 2735);
FORCEPROP 1 LASTPIN (-5525 2725) BN 24
J 0
(-5577 2733);
DISPLAY 0.617021 (-5577 2733);
PAINT GREEN (-5577 2733);
FORCEPROP 2 LAST CDS_LIB mstr_standard
J 0
(-5575 2725);
PAINT MONO (-5575 2725);
DISPLAY INVISIBLE (-5575 2725);
FORCEPROP 1 LAST BODY_TYPE PLUMBING
J 0
(-5575 2675);
DISPLAY 1.595745 (-5575 2675);
PAINT GREEN (-5575 2675);
DISPLAY INVISIBLE (-5575 2675);
FORCEPROP 1 LAST HDL_TAP TRUE
J 0
(-5250 2600);
DISPLAY 1.595745 (-5250 2600);
PAINT GREEN (-5250 2600);
DISPLAY INVISIBLE (-5250 2600);
FORCEPROP 1 LAST PATH I46
J 0
(-5577 2725);
DISPLAY 0.872340 (-5577 2725);
PAINT GREEN (-5577 2725);
DISPLAY INVISIBLE (-5577 2725);
FORCEADD TAP..6
(-5575 2825);
FORCEPROP 3 LASTPIN (-5525 2825) SIG_NAME M_L_DQ<26>
J 0
(-5515 2835);
DISPLAY 0.659574 (-5515 2835);
PAINT MONO (-5515 2835);
DISPLAY INVISIBLE (-5515 2835);
FORCEPROP 1 LASTPIN (-5525 2825) BN 26
J 0
(-5577 2833);
DISPLAY 0.617021 (-5577 2833);
PAINT GREEN (-5577 2833);
FORCEPROP 2 LAST CDS_LIB mstr_standard
J 0
(-5575 2825);
PAINT MONO (-5575 2825);
DISPLAY INVISIBLE (-5575 2825);
FORCEPROP 1 LAST BODY_TYPE PLUMBING
J 0
(-5575 2775);
DISPLAY 1.595745 (-5575 2775);
PAINT GREEN (-5575 2775);
DISPLAY INVISIBLE (-5575 2775);
FORCEPROP 1 LAST HDL_TAP TRUE
J 0
(-5250 2700);
DISPLAY 1.595745 (-5250 2700);
PAINT GREEN (-5250 2700);
DISPLAY INVISIBLE (-5250 2700);
FORCEPROP 1 LAST PATH I47
J 0
(-5577 2825);
DISPLAY 0.872340 (-5577 2825);
PAINT GREEN (-5577 2825);
DISPLAY INVISIBLE (-5577 2825);
FORCEADD TAP..6
(-5575 2775);
FORCEPROP 3 LASTPIN (-5525 2775) SIG_NAME M_L_DQ<25>
J 0
(-5515 2785);
DISPLAY 0.659574 (-5515 2785);
PAINT MONO (-5515 2785);
DISPLAY INVISIBLE (-5515 2785);
FORCEPROP 1 LASTPIN (-5525 2775) BN 25
J 0
(-5577 2783);
DISPLAY 0.617021 (-5577 2783);
PAINT GREEN (-5577 2783);
FORCEPROP 2 LAST CDS_LIB mstr_standard
J 0
(-5575 2775);
PAINT MONO (-5575 2775);
DISPLAY INVISIBLE (-5575 2775);
FORCEPROP 1 LAST BODY_TYPE PLUMBING
J 0
(-5575 2725);
DISPLAY 1.595745 (-5575 2725);
PAINT GREEN (-5575 2725);
DISPLAY INVISIBLE (-5575 2725);
FORCEPROP 1 LAST HDL_TAP TRUE
J 0
(-5250 2650);
DISPLAY 1.595745 (-5250 2650);
PAINT GREEN (-5250 2650);
DISPLAY INVISIBLE (-5250 2650);
FORCEPROP 1 LAST PATH I48
J 0
(-5577 2775);
DISPLAY 0.872340 (-5577 2775);
PAINT GREEN (-5577 2775);
DISPLAY INVISIBLE (-5577 2775);
FORCEADD TAP..6
(-5575 2875);
FORCEPROP 3 LASTPIN (-5525 2875) SIG_NAME M_L_DQ<27>
J 0
(-5515 2885);
DISPLAY 0.659574 (-5515 2885);
PAINT MONO (-5515 2885);
DISPLAY INVISIBLE (-5515 2885);
FORCEPROP 1 LASTPIN (-5525 2875) BN 27
J 0
(-5577 2883);
DISPLAY 0.617021 (-5577 2883);
PAINT GREEN (-5577 2883);
FORCEPROP 2 LAST CDS_LIB mstr_standard
J 0
(-5575 2875);
PAINT MONO (-5575 2875);
DISPLAY INVISIBLE (-5575 2875);
FORCEPROP 1 LAST BODY_TYPE PLUMBING
J 0
(-5575 2825);
DISPLAY 1.595745 (-5575 2825);
PAINT GREEN (-5575 2825);
DISPLAY INVISIBLE (-5575 2825);
FORCEPROP 1 LAST HDL_TAP TRUE
J 0
(-5250 2750);
DISPLAY 1.595745 (-5250 2750);
PAINT GREEN (-5250 2750);
DISPLAY INVISIBLE (-5250 2750);
FORCEPROP 1 LAST PATH I49
J 0
(-5577 2875);
DISPLAY 0.872340 (-5577 2875);
PAINT GREEN (-5577 2875);
DISPLAY INVISIBLE (-5577 2875);
FORCEADD TAP..6
(-5575 625);
FORCEPROP 3 LASTPIN (-5525 625) SIG_NAME M_L_CLK_DN<0>
J 0
(-5515 635);
DISPLAY 0.659574 (-5515 635);
PAINT MONO (-5515 635);
DISPLAY INVISIBLE (-5515 635);
FORCEPROP 1 LASTPIN (-5525 625) BN 0
J 0
(-5577 633);
DISPLAY 0.617021 (-5577 633);
PAINT GREEN (-5577 633);
FORCEPROP 2 LAST CDS_LIB mstr_standard
J 0
(-5575 625);
PAINT MONO (-5575 625);
DISPLAY INVISIBLE (-5575 625);
FORCEPROP 1 LAST BODY_TYPE PLUMBING
J 0
(-5575 575);
DISPLAY 1.595745 (-5575 575);
PAINT GREEN (-5575 575);
DISPLAY INVISIBLE (-5575 575);
FORCEPROP 1 LAST HDL_TAP TRUE
J 0
(-5250 500);
DISPLAY 1.595745 (-5250 500);
PAINT GREEN (-5250 500);
DISPLAY INVISIBLE (-5250 500);
FORCEPROP 1 LAST PATH I5
J 0
(-5577 625);
DISPLAY 0.872340 (-5577 625);
PAINT GREEN (-5577 625);
DISPLAY INVISIBLE (-5577 625);
FORCEADD TAP..6
(-5575 2925);
FORCEPROP 3 LASTPIN (-5525 2925) SIG_NAME M_L_DQ<28>
J 0
(-5515 2935);
DISPLAY 0.659574 (-5515 2935);
PAINT MONO (-5515 2935);
DISPLAY INVISIBLE (-5515 2935);
FORCEPROP 1 LASTPIN (-5525 2925) BN 28
J 0
(-5577 2933);
DISPLAY 0.617021 (-5577 2933);
PAINT GREEN (-5577 2933);
FORCEPROP 2 LAST CDS_LIB mstr_standard
J 0
(-5575 2925);
PAINT MONO (-5575 2925);
DISPLAY INVISIBLE (-5575 2925);
FORCEPROP 1 LAST BODY_TYPE PLUMBING
J 0
(-5575 2875);
DISPLAY 1.595745 (-5575 2875);
PAINT GREEN (-5575 2875);
DISPLAY INVISIBLE (-5575 2875);
FORCEPROP 1 LAST HDL_TAP TRUE
J 0
(-5250 2800);
DISPLAY 1.595745 (-5250 2800);
PAINT GREEN (-5250 2800);
DISPLAY INVISIBLE (-5250 2800);
FORCEPROP 1 LAST PATH I50
J 0
(-5577 2925);
DISPLAY 0.872340 (-5577 2925);
PAINT GREEN (-5577 2925);
DISPLAY INVISIBLE (-5577 2925);
FORCEADD TAP..6
(-5575 2975);
FORCEPROP 3 LASTPIN (-5525 2975) SIG_NAME M_L_DQ<29>
J 0
(-5515 2985);
DISPLAY 0.659574 (-5515 2985);
PAINT MONO (-5515 2985);
DISPLAY INVISIBLE (-5515 2985);
FORCEPROP 1 LASTPIN (-5525 2975) BN 29
J 0
(-5577 2983);
DISPLAY 0.617021 (-5577 2983);
PAINT GREEN (-5577 2983);
FORCEPROP 2 LAST CDS_LIB mstr_standard
J 0
(-5575 2975);
PAINT MONO (-5575 2975);
DISPLAY INVISIBLE (-5575 2975);
FORCEPROP 1 LAST BODY_TYPE PLUMBING
J 0
(-5575 2925);
DISPLAY 1.595745 (-5575 2925);
PAINT GREEN (-5575 2925);
DISPLAY INVISIBLE (-5575 2925);
FORCEPROP 1 LAST HDL_TAP TRUE
J 0
(-5250 2850);
DISPLAY 1.595745 (-5250 2850);
PAINT GREEN (-5250 2850);
DISPLAY INVISIBLE (-5250 2850);
FORCEPROP 1 LAST PATH I51
J 0
(-5577 2975);
DISPLAY 0.872340 (-5577 2975);
PAINT GREEN (-5577 2975);
DISPLAY INVISIBLE (-5577 2975);
FORCEADD TAP..6
(-5575 3075);
FORCEPROP 3 LASTPIN (-5525 3075) SIG_NAME M_L_DQ<31>
J 0
(-5515 3085);
DISPLAY 0.659574 (-5515 3085);
PAINT MONO (-5515 3085);
DISPLAY INVISIBLE (-5515 3085);
FORCEPROP 1 LASTPIN (-5525 3075) BN 31
J 0
(-5577 3083);
DISPLAY 0.617021 (-5577 3083);
PAINT GREEN (-5577 3083);
FORCEPROP 2 LAST CDS_LIB mstr_standard
J 0
(-5575 3075);
PAINT MONO (-5575 3075);
DISPLAY INVISIBLE (-5575 3075);
FORCEPROP 1 LAST BODY_TYPE PLUMBING
J 0
(-5575 3025);
DISPLAY 1.595745 (-5575 3025);
PAINT GREEN (-5575 3025);
DISPLAY INVISIBLE (-5575 3025);
FORCEPROP 1 LAST HDL_TAP TRUE
J 0
(-5250 2950);
DISPLAY 1.595745 (-5250 2950);
PAINT GREEN (-5250 2950);
DISPLAY INVISIBLE (-5250 2950);
FORCEPROP 1 LAST PATH I52
J 0
(-5577 3075);
DISPLAY 0.872340 (-5577 3075);
PAINT GREEN (-5577 3075);
DISPLAY INVISIBLE (-5577 3075);
FORCEADD TAP..6
(-5575 3025);
FORCEPROP 3 LASTPIN (-5525 3025) SIG_NAME M_L_DQ<30>
J 0
(-5515 3035);
DISPLAY 0.659574 (-5515 3035);
PAINT MONO (-5515 3035);
DISPLAY INVISIBLE (-5515 3035);
FORCEPROP 1 LASTPIN (-5525 3025) BN 30
J 0
(-5577 3033);
DISPLAY 0.617021 (-5577 3033);
PAINT GREEN (-5577 3033);
FORCEPROP 2 LAST CDS_LIB mstr_standard
J 0
(-5575 3025);
PAINT MONO (-5575 3025);
DISPLAY INVISIBLE (-5575 3025);
FORCEPROP 1 LAST BODY_TYPE PLUMBING
J 0
(-5575 2975);
DISPLAY 1.595745 (-5575 2975);
PAINT GREEN (-5575 2975);
DISPLAY INVISIBLE (-5575 2975);
FORCEPROP 1 LAST HDL_TAP TRUE
J 0
(-5250 2900);
DISPLAY 1.595745 (-5250 2900);
PAINT GREEN (-5250 2900);
DISPLAY INVISIBLE (-5250 2900);
FORCEPROP 1 LAST PATH I53
J 0
(-5577 3025);
DISPLAY 0.872340 (-5577 3025);
PAINT GREEN (-5577 3025);
DISPLAY INVISIBLE (-5577 3025);
FORCEADD TAP..6
(-5575 3125);
FORCEPROP 3 LASTPIN (-5525 3125) SIG_NAME M_L_DQ<32>
J 0
(-5515 3135);
DISPLAY 0.659574 (-5515 3135);
PAINT MONO (-5515 3135);
DISPLAY INVISIBLE (-5515 3135);
FORCEPROP 1 LASTPIN (-5525 3125) BN 32
J 0
(-5577 3133);
DISPLAY 0.617021 (-5577 3133);
PAINT GREEN (-5577 3133);
FORCEPROP 2 LAST CDS_LIB mstr_standard
J 0
(-5575 3125);
PAINT MONO (-5575 3125);
DISPLAY INVISIBLE (-5575 3125);
FORCEPROP 1 LAST BODY_TYPE PLUMBING
J 0
(-5575 3075);
DISPLAY 1.595745 (-5575 3075);
PAINT GREEN (-5575 3075);
DISPLAY INVISIBLE (-5575 3075);
FORCEPROP 1 LAST HDL_TAP TRUE
J 0
(-5250 3000);
DISPLAY 1.595745 (-5250 3000);
PAINT GREEN (-5250 3000);
DISPLAY INVISIBLE (-5250 3000);
FORCEPROP 1 LAST PATH I54
J 0
(-5577 3125);
DISPLAY 0.872340 (-5577 3125);
PAINT GREEN (-5577 3125);
DISPLAY INVISIBLE (-5577 3125);
FORCEADD TAP..6
(-5575 3175);
FORCEPROP 3 LASTPIN (-5525 3175) SIG_NAME M_L_DQ<33>
J 0
(-5515 3185);
DISPLAY 0.659574 (-5515 3185);
PAINT MONO (-5515 3185);
DISPLAY INVISIBLE (-5515 3185);
FORCEPROP 1 LASTPIN (-5525 3175) BN 33
J 0
(-5577 3183);
DISPLAY 0.617021 (-5577 3183);
PAINT GREEN (-5577 3183);
FORCEPROP 2 LAST CDS_LIB mstr_standard
J 0
(-5575 3175);
PAINT MONO (-5575 3175);
DISPLAY INVISIBLE (-5575 3175);
FORCEPROP 1 LAST BODY_TYPE PLUMBING
J 0
(-5575 3125);
DISPLAY 1.595745 (-5575 3125);
PAINT GREEN (-5575 3125);
DISPLAY INVISIBLE (-5575 3125);
FORCEPROP 1 LAST HDL_TAP TRUE
J 0
(-5250 3050);
DISPLAY 1.595745 (-5250 3050);
PAINT GREEN (-5250 3050);
DISPLAY INVISIBLE (-5250 3050);
FORCEPROP 1 LAST PATH I55
J 0
(-5577 3175);
DISPLAY 0.872340 (-5577 3175);
PAINT GREEN (-5577 3175);
DISPLAY INVISIBLE (-5577 3175);
FORCEADD TAP..6
(-5575 3225);
FORCEPROP 3 LASTPIN (-5525 3225) SIG_NAME M_L_DQ<34>
J 0
(-5515 3235);
DISPLAY 0.659574 (-5515 3235);
PAINT MONO (-5515 3235);
DISPLAY INVISIBLE (-5515 3235);
FORCEPROP 1 LASTPIN (-5525 3225) BN 34
J 0
(-5577 3233);
DISPLAY 0.617021 (-5577 3233);
PAINT GREEN (-5577 3233);
FORCEPROP 2 LAST CDS_LIB mstr_standard
J 0
(-5575 3225);
PAINT MONO (-5575 3225);
DISPLAY INVISIBLE (-5575 3225);
FORCEPROP 1 LAST BODY_TYPE PLUMBING
J 0
(-5575 3175);
DISPLAY 1.595745 (-5575 3175);
PAINT GREEN (-5575 3175);
DISPLAY INVISIBLE (-5575 3175);
FORCEPROP 1 LAST HDL_TAP TRUE
J 0
(-5250 3100);
DISPLAY 1.595745 (-5250 3100);
PAINT GREEN (-5250 3100);
DISPLAY INVISIBLE (-5250 3100);
FORCEPROP 1 LAST PATH I56
J 0
(-5577 3225);
DISPLAY 0.872340 (-5577 3225);
PAINT GREEN (-5577 3225);
DISPLAY INVISIBLE (-5577 3225);
FORCEADD TAP..6
(-5575 3325);
FORCEPROP 3 LASTPIN (-5525 3325) SIG_NAME M_L_DQ<36>
J 0
(-5515 3335);
DISPLAY 0.659574 (-5515 3335);
PAINT MONO (-5515 3335);
DISPLAY INVISIBLE (-5515 3335);
FORCEPROP 1 LASTPIN (-5525 3325) BN 36
J 0
(-5577 3333);
DISPLAY 0.617021 (-5577 3333);
PAINT GREEN (-5577 3333);
FORCEPROP 2 LAST CDS_LIB mstr_standard
J 0
(-5575 3325);
PAINT MONO (-5575 3325);
DISPLAY INVISIBLE (-5575 3325);
FORCEPROP 1 LAST BODY_TYPE PLUMBING
J 0
(-5575 3275);
DISPLAY 1.595745 (-5575 3275);
PAINT GREEN (-5575 3275);
DISPLAY INVISIBLE (-5575 3275);
FORCEPROP 1 LAST HDL_TAP TRUE
J 0
(-5250 3200);
DISPLAY 1.595745 (-5250 3200);
PAINT GREEN (-5250 3200);
DISPLAY INVISIBLE (-5250 3200);
FORCEPROP 1 LAST PATH I57
J 0
(-5577 3325);
DISPLAY 0.872340 (-5577 3325);
PAINT GREEN (-5577 3325);
DISPLAY INVISIBLE (-5577 3325);
FORCEADD TAP..6
(-5575 3275);
FORCEPROP 3 LASTPIN (-5525 3275) SIG_NAME M_L_DQ<35>
J 0
(-5515 3285);
DISPLAY 0.659574 (-5515 3285);
PAINT MONO (-5515 3285);
DISPLAY INVISIBLE (-5515 3285);
FORCEPROP 1 LASTPIN (-5525 3275) BN 35
J 0
(-5577 3283);
DISPLAY 0.617021 (-5577 3283);
PAINT GREEN (-5577 3283);
FORCEPROP 2 LAST CDS_LIB mstr_standard
J 0
(-5575 3275);
PAINT MONO (-5575 3275);
DISPLAY INVISIBLE (-5575 3275);
FORCEPROP 1 LAST BODY_TYPE PLUMBING
J 0
(-5575 3225);
DISPLAY 1.595745 (-5575 3225);
PAINT GREEN (-5575 3225);
DISPLAY INVISIBLE (-5575 3225);
FORCEPROP 1 LAST HDL_TAP TRUE
J 0
(-5250 3150);
DISPLAY 1.595745 (-5250 3150);
PAINT GREEN (-5250 3150);
DISPLAY INVISIBLE (-5250 3150);
FORCEPROP 1 LAST PATH I58
J 0
(-5577 3275);
DISPLAY 0.872340 (-5577 3275);
PAINT GREEN (-5577 3275);
DISPLAY INVISIBLE (-5577 3275);
FORCEADD TAP..6
(-5575 3375);
FORCEPROP 3 LASTPIN (-5525 3375) SIG_NAME M_L_DQ<37>
J 0
(-5515 3385);
DISPLAY 0.659574 (-5515 3385);
PAINT MONO (-5515 3385);
DISPLAY INVISIBLE (-5515 3385);
FORCEPROP 1 LASTPIN (-5525 3375) BN 37
J 0
(-5577 3383);
DISPLAY 0.617021 (-5577 3383);
PAINT GREEN (-5577 3383);
FORCEPROP 2 LAST CDS_LIB mstr_standard
J 0
(-5575 3375);
PAINT MONO (-5575 3375);
DISPLAY INVISIBLE (-5575 3375);
FORCEPROP 1 LAST BODY_TYPE PLUMBING
J 0
(-5575 3325);
DISPLAY 1.595745 (-5575 3325);
PAINT GREEN (-5575 3325);
DISPLAY INVISIBLE (-5575 3325);
FORCEPROP 1 LAST HDL_TAP TRUE
J 0
(-5250 3250);
DISPLAY 1.595745 (-5250 3250);
PAINT GREEN (-5250 3250);
DISPLAY INVISIBLE (-5250 3250);
FORCEPROP 1 LAST PATH I59
J 0
(-5577 3375);
DISPLAY 0.872340 (-5577 3375);
PAINT GREEN (-5577 3375);
DISPLAY INVISIBLE (-5577 3375);
FORCEADD TAP..6
(-5575 675);
FORCEPROP 3 LASTPIN (-5525 675) SIG_NAME M_L_CLK_DN<1>
J 0
(-5515 685);
DISPLAY 0.659574 (-5515 685);
PAINT MONO (-5515 685);
DISPLAY INVISIBLE (-5515 685);
FORCEPROP 1 LASTPIN (-5525 675) BN 1
J 0
(-5577 683);
DISPLAY 0.617021 (-5577 683);
PAINT GREEN (-5577 683);
FORCEPROP 2 LAST CDS_LIB mstr_standard
J 0
(-5575 675);
PAINT MONO (-5575 675);
DISPLAY INVISIBLE (-5575 675);
FORCEPROP 1 LAST BODY_TYPE PLUMBING
J 0
(-5575 625);
DISPLAY 1.595745 (-5575 625);
PAINT GREEN (-5575 625);
DISPLAY INVISIBLE (-5575 625);
FORCEPROP 1 LAST HDL_TAP TRUE
J 0
(-5250 550);
DISPLAY 1.595745 (-5250 550);
PAINT GREEN (-5250 550);
DISPLAY INVISIBLE (-5250 550);
FORCEPROP 1 LAST PATH I6
J 0
(-5577 675);
DISPLAY 0.872340 (-5577 675);
PAINT GREEN (-5577 675);
DISPLAY INVISIBLE (-5577 675);
FORCEADD TAP..6
(-5575 3425);
FORCEPROP 3 LASTPIN (-5525 3425) SIG_NAME M_L_DQ<38>
J 0
(-5515 3435);
DISPLAY 0.659574 (-5515 3435);
PAINT MONO (-5515 3435);
DISPLAY INVISIBLE (-5515 3435);
FORCEPROP 1 LASTPIN (-5525 3425) BN 38
J 0
(-5577 3433);
DISPLAY 0.617021 (-5577 3433);
PAINT GREEN (-5577 3433);
FORCEPROP 2 LAST CDS_LIB mstr_standard
J 0
(-5575 3425);
PAINT MONO (-5575 3425);
DISPLAY INVISIBLE (-5575 3425);
FORCEPROP 1 LAST BODY_TYPE PLUMBING
J 0
(-5575 3375);
DISPLAY 1.595745 (-5575 3375);
PAINT GREEN (-5575 3375);
DISPLAY INVISIBLE (-5575 3375);
FORCEPROP 1 LAST HDL_TAP TRUE
J 0
(-5250 3300);
DISPLAY 1.595745 (-5250 3300);
PAINT GREEN (-5250 3300);
DISPLAY INVISIBLE (-5250 3300);
FORCEPROP 1 LAST PATH I60
J 0
(-5577 3425);
DISPLAY 0.872340 (-5577 3425);
PAINT GREEN (-5577 3425);
DISPLAY INVISIBLE (-5577 3425);
FORCEADD TAP..6
(-5575 3475);
FORCEPROP 3 LASTPIN (-5525 3475) SIG_NAME M_L_DQ<39>
J 0
(-5515 3485);
DISPLAY 0.659574 (-5515 3485);
PAINT MONO (-5515 3485);
DISPLAY INVISIBLE (-5515 3485);
FORCEPROP 1 LASTPIN (-5525 3475) BN 39
J 0
(-5577 3483);
DISPLAY 0.617021 (-5577 3483);
PAINT GREEN (-5577 3483);
FORCEPROP 2 LAST CDS_LIB mstr_standard
J 0
(-5575 3475);
PAINT MONO (-5575 3475);
DISPLAY INVISIBLE (-5575 3475);
FORCEPROP 1 LAST BODY_TYPE PLUMBING
J 0
(-5575 3425);
DISPLAY 1.595745 (-5575 3425);
PAINT GREEN (-5575 3425);
DISPLAY INVISIBLE (-5575 3425);
FORCEPROP 1 LAST HDL_TAP TRUE
J 0
(-5250 3350);
DISPLAY 1.595745 (-5250 3350);
PAINT GREEN (-5250 3350);
DISPLAY INVISIBLE (-5250 3350);
FORCEPROP 1 LAST PATH I61
J 0
(-5577 3475);
DISPLAY 0.872340 (-5577 3475);
PAINT GREEN (-5577 3475);
DISPLAY INVISIBLE (-5577 3475);
FORCEADD TAP..6
(-5575 3525);
FORCEPROP 3 LASTPIN (-5525 3525) SIG_NAME M_L_DQ<40>
J 0
(-5515 3535);
DISPLAY 0.659574 (-5515 3535);
PAINT MONO (-5515 3535);
DISPLAY INVISIBLE (-5515 3535);
FORCEPROP 1 LASTPIN (-5525 3525) BN 40
J 0
(-5577 3533);
DISPLAY 0.617021 (-5577 3533);
PAINT GREEN (-5577 3533);
FORCEPROP 2 LAST CDS_LIB mstr_standard
J 0
(-5575 3525);
PAINT MONO (-5575 3525);
DISPLAY INVISIBLE (-5575 3525);
FORCEPROP 1 LAST BODY_TYPE PLUMBING
J 0
(-5575 3475);
DISPLAY 1.595745 (-5575 3475);
PAINT GREEN (-5575 3475);
DISPLAY INVISIBLE (-5575 3475);
FORCEPROP 1 LAST HDL_TAP TRUE
J 0
(-5250 3400);
DISPLAY 1.595745 (-5250 3400);
PAINT GREEN (-5250 3400);
DISPLAY INVISIBLE (-5250 3400);
FORCEPROP 1 LAST PATH I62
J 0
(-5577 3525);
DISPLAY 0.872340 (-5577 3525);
PAINT GREEN (-5577 3525);
DISPLAY INVISIBLE (-5577 3525);
FORCEADD TAP..6
(-5575 3575);
FORCEPROP 3 LASTPIN (-5525 3575) SIG_NAME M_L_DQ<41>
J 0
(-5515 3585);
DISPLAY 0.659574 (-5515 3585);
PAINT MONO (-5515 3585);
DISPLAY INVISIBLE (-5515 3585);
FORCEPROP 1 LASTPIN (-5525 3575) BN 41
J 0
(-5577 3583);
DISPLAY 0.617021 (-5577 3583);
PAINT GREEN (-5577 3583);
FORCEPROP 2 LAST CDS_LIB mstr_standard
J 0
(-5575 3575);
PAINT MONO (-5575 3575);
DISPLAY INVISIBLE (-5575 3575);
FORCEPROP 1 LAST BODY_TYPE PLUMBING
J 0
(-5575 3525);
DISPLAY 1.595745 (-5575 3525);
PAINT GREEN (-5575 3525);
DISPLAY INVISIBLE (-5575 3525);
FORCEPROP 1 LAST HDL_TAP TRUE
J 0
(-5250 3450);
DISPLAY 1.595745 (-5250 3450);
PAINT GREEN (-5250 3450);
DISPLAY INVISIBLE (-5250 3450);
FORCEPROP 1 LAST PATH I63
J 0
(-5577 3575);
DISPLAY 0.872340 (-5577 3575);
PAINT GREEN (-5577 3575);
DISPLAY INVISIBLE (-5577 3575);
FORCEADD TAP..6
(-5575 3625);
FORCEPROP 3 LASTPIN (-5525 3625) SIG_NAME M_L_DQ<42>
J 0
(-5515 3635);
DISPLAY 0.659574 (-5515 3635);
PAINT MONO (-5515 3635);
DISPLAY INVISIBLE (-5515 3635);
FORCEPROP 1 LASTPIN (-5525 3625) BN 42
J 0
(-5577 3633);
DISPLAY 0.617021 (-5577 3633);
PAINT GREEN (-5577 3633);
FORCEPROP 2 LAST CDS_LIB mstr_standard
J 0
(-5575 3625);
PAINT MONO (-5575 3625);
DISPLAY INVISIBLE (-5575 3625);
FORCEPROP 1 LAST BODY_TYPE PLUMBING
J 0
(-5575 3575);
DISPLAY 1.595745 (-5575 3575);
PAINT GREEN (-5575 3575);
DISPLAY INVISIBLE (-5575 3575);
FORCEPROP 1 LAST HDL_TAP TRUE
J 0
(-5250 3500);
DISPLAY 1.595745 (-5250 3500);
PAINT GREEN (-5250 3500);
DISPLAY INVISIBLE (-5250 3500);
FORCEPROP 1 LAST PATH I64
J 0
(-5577 3625);
DISPLAY 0.872340 (-5577 3625);
PAINT GREEN (-5577 3625);
DISPLAY INVISIBLE (-5577 3625);
FORCEADD TAP..6
(-5575 3675);
FORCEPROP 3 LASTPIN (-5525 3675) SIG_NAME M_L_DQ<43>
J 0
(-5515 3685);
DISPLAY 0.659574 (-5515 3685);
PAINT MONO (-5515 3685);
DISPLAY INVISIBLE (-5515 3685);
FORCEPROP 1 LASTPIN (-5525 3675) BN 43
J 0
(-5577 3683);
DISPLAY 0.617021 (-5577 3683);
PAINT GREEN (-5577 3683);
FORCEPROP 2 LAST CDS_LIB mstr_standard
J 0
(-5575 3675);
PAINT MONO (-5575 3675);
DISPLAY INVISIBLE (-5575 3675);
FORCEPROP 1 LAST BODY_TYPE PLUMBING
J 0
(-5575 3625);
DISPLAY 1.595745 (-5575 3625);
PAINT GREEN (-5575 3625);
DISPLAY INVISIBLE (-5575 3625);
FORCEPROP 1 LAST HDL_TAP TRUE
J 0
(-5250 3550);
DISPLAY 1.595745 (-5250 3550);
PAINT GREEN (-5250 3550);
DISPLAY INVISIBLE (-5250 3550);
FORCEPROP 1 LAST PATH I65
J 0
(-5577 3675);
DISPLAY 0.872340 (-5577 3675);
PAINT GREEN (-5577 3675);
DISPLAY INVISIBLE (-5577 3675);
FORCEADD TAP..6
(-5575 3725);
FORCEPROP 3 LASTPIN (-5525 3725) SIG_NAME M_L_DQ<44>
J 0
(-5515 3735);
DISPLAY 0.659574 (-5515 3735);
PAINT MONO (-5515 3735);
DISPLAY INVISIBLE (-5515 3735);
FORCEPROP 1 LASTPIN (-5525 3725) BN 44
J 0
(-5577 3733);
DISPLAY 0.617021 (-5577 3733);
PAINT GREEN (-5577 3733);
FORCEPROP 2 LAST CDS_LIB mstr_standard
J 0
(-5575 3725);
PAINT MONO (-5575 3725);
DISPLAY INVISIBLE (-5575 3725);
FORCEPROP 1 LAST BODY_TYPE PLUMBING
J 0
(-5575 3675);
DISPLAY 1.595745 (-5575 3675);
PAINT GREEN (-5575 3675);
DISPLAY INVISIBLE (-5575 3675);
FORCEPROP 1 LAST HDL_TAP TRUE
J 0
(-5250 3600);
DISPLAY 1.595745 (-5250 3600);
PAINT GREEN (-5250 3600);
DISPLAY INVISIBLE (-5250 3600);
FORCEPROP 1 LAST PATH I66
J 0
(-5577 3725);
DISPLAY 0.872340 (-5577 3725);
PAINT GREEN (-5577 3725);
DISPLAY INVISIBLE (-5577 3725);
FORCEADD TAP..6
(-5575 3775);
FORCEPROP 3 LASTPIN (-5525 3775) SIG_NAME M_L_DQ<45>
J 0
(-5515 3785);
DISPLAY 0.659574 (-5515 3785);
PAINT MONO (-5515 3785);
DISPLAY INVISIBLE (-5515 3785);
FORCEPROP 1 LASTPIN (-5525 3775) BN 45
J 0
(-5577 3783);
DISPLAY 0.617021 (-5577 3783);
PAINT GREEN (-5577 3783);
FORCEPROP 2 LAST CDS_LIB mstr_standard
J 0
(-5575 3775);
PAINT MONO (-5575 3775);
DISPLAY INVISIBLE (-5575 3775);
FORCEPROP 1 LAST BODY_TYPE PLUMBING
J 0
(-5575 3725);
DISPLAY 1.595745 (-5575 3725);
PAINT GREEN (-5575 3725);
DISPLAY INVISIBLE (-5575 3725);
FORCEPROP 1 LAST HDL_TAP TRUE
J 0
(-5250 3650);
DISPLAY 1.595745 (-5250 3650);
PAINT GREEN (-5250 3650);
DISPLAY INVISIBLE (-5250 3650);
FORCEPROP 1 LAST PATH I67
J 0
(-5577 3775);
DISPLAY 0.872340 (-5577 3775);
PAINT GREEN (-5577 3775);
DISPLAY INVISIBLE (-5577 3775);
FORCEADD TAP..6
(-5575 3825);
FORCEPROP 3 LASTPIN (-5525 3825) SIG_NAME M_L_DQ<46>
J 0
(-5515 3835);
DISPLAY 0.659574 (-5515 3835);
PAINT MONO (-5515 3835);
DISPLAY INVISIBLE (-5515 3835);
FORCEPROP 1 LASTPIN (-5525 3825) BN 46
J 0
(-5577 3833);
DISPLAY 0.617021 (-5577 3833);
PAINT GREEN (-5577 3833);
FORCEPROP 2 LAST CDS_LIB mstr_standard
J 0
(-5575 3825);
PAINT MONO (-5575 3825);
DISPLAY INVISIBLE (-5575 3825);
FORCEPROP 1 LAST BODY_TYPE PLUMBING
J 0
(-5575 3775);
DISPLAY 1.595745 (-5575 3775);
PAINT GREEN (-5575 3775);
DISPLAY INVISIBLE (-5575 3775);
FORCEPROP 1 LAST HDL_TAP TRUE
J 0
(-5250 3700);
DISPLAY 1.595745 (-5250 3700);
PAINT GREEN (-5250 3700);
DISPLAY INVISIBLE (-5250 3700);
FORCEPROP 1 LAST PATH I68
J 0
(-5577 3825);
DISPLAY 0.872340 (-5577 3825);
PAINT GREEN (-5577 3825);
DISPLAY INVISIBLE (-5577 3825);
FORCEADD TAP..6
(-5575 3875);
FORCEPROP 3 LASTPIN (-5525 3875) SIG_NAME M_L_DQ<47>
J 0
(-5515 3885);
DISPLAY 0.659574 (-5515 3885);
PAINT MONO (-5515 3885);
DISPLAY INVISIBLE (-5515 3885);
FORCEPROP 1 LASTPIN (-5525 3875) BN 47
J 0
(-5577 3883);
DISPLAY 0.617021 (-5577 3883);
PAINT GREEN (-5577 3883);
FORCEPROP 2 LAST CDS_LIB mstr_standard
J 0
(-5575 3875);
PAINT MONO (-5575 3875);
DISPLAY INVISIBLE (-5575 3875);
FORCEPROP 1 LAST BODY_TYPE PLUMBING
J 0
(-5575 3825);
DISPLAY 1.595745 (-5575 3825);
PAINT GREEN (-5575 3825);
DISPLAY INVISIBLE (-5575 3825);
FORCEPROP 1 LAST HDL_TAP TRUE
J 0
(-5250 3750);
DISPLAY 1.595745 (-5250 3750);
PAINT GREEN (-5250 3750);
DISPLAY INVISIBLE (-5250 3750);
FORCEPROP 1 LAST PATH I69
J 0
(-5577 3875);
DISPLAY 0.872340 (-5577 3875);
PAINT GREEN (-5577 3875);
DISPLAY INVISIBLE (-5577 3875);
FORCEADD TAP..6
(-5575 775);
FORCEPROP 3 LASTPIN (-5525 775) SIG_NAME M_L_CLK_DN<3>
J 0
(-5515 785);
DISPLAY 0.659574 (-5515 785);
PAINT MONO (-5515 785);
DISPLAY INVISIBLE (-5515 785);
FORCEPROP 1 LASTPIN (-5525 775) BN 3
J 0
(-5577 783);
DISPLAY 0.617021 (-5577 783);
PAINT GREEN (-5577 783);
FORCEPROP 2 LAST CDS_LIB mstr_standard
J 0
(-5575 775);
PAINT MONO (-5575 775);
DISPLAY INVISIBLE (-5575 775);
FORCEPROP 1 LAST BODY_TYPE PLUMBING
J 0
(-5575 725);
DISPLAY 1.595745 (-5575 725);
PAINT GREEN (-5575 725);
DISPLAY INVISIBLE (-5575 725);
FORCEPROP 1 LAST HDL_TAP TRUE
J 0
(-5250 650);
DISPLAY 1.595745 (-5250 650);
PAINT GREEN (-5250 650);
DISPLAY INVISIBLE (-5250 650);
FORCEPROP 1 LAST PATH I7
J 0
(-5577 775);
DISPLAY 0.872340 (-5577 775);
PAINT GREEN (-5577 775);
DISPLAY INVISIBLE (-5577 775);
FORCEADD TAP..6
(-5575 3925);
FORCEPROP 3 LASTPIN (-5525 3925) SIG_NAME M_L_DQ<48>
J 0
(-5515 3935);
DISPLAY 0.659574 (-5515 3935);
PAINT MONO (-5515 3935);
DISPLAY INVISIBLE (-5515 3935);
FORCEPROP 1 LASTPIN (-5525 3925) BN 48
J 0
(-5577 3933);
DISPLAY 0.617021 (-5577 3933);
PAINT GREEN (-5577 3933);
FORCEPROP 2 LAST CDS_LIB mstr_standard
J 0
(-5575 3925);
PAINT MONO (-5575 3925);
DISPLAY INVISIBLE (-5575 3925);
FORCEPROP 1 LAST BODY_TYPE PLUMBING
J 0
(-5575 3875);
DISPLAY 1.595745 (-5575 3875);
PAINT GREEN (-5575 3875);
DISPLAY INVISIBLE (-5575 3875);
FORCEPROP 1 LAST HDL_TAP TRUE
J 0
(-5250 3800);
DISPLAY 1.595745 (-5250 3800);
PAINT GREEN (-5250 3800);
DISPLAY INVISIBLE (-5250 3800);
FORCEPROP 1 LAST PATH I70
J 0
(-5577 3925);
DISPLAY 0.872340 (-5577 3925);
PAINT GREEN (-5577 3925);
DISPLAY INVISIBLE (-5577 3925);
FORCEADD TAP..6
(-5575 3975);
FORCEPROP 3 LASTPIN (-5525 3975) SIG_NAME M_L_DQ<49>
J 0
(-5515 3985);
DISPLAY 0.659574 (-5515 3985);
PAINT MONO (-5515 3985);
DISPLAY INVISIBLE (-5515 3985);
FORCEPROP 1 LASTPIN (-5525 3975) BN 49
J 0
(-5577 3983);
DISPLAY 0.617021 (-5577 3983);
PAINT GREEN (-5577 3983);
FORCEPROP 2 LAST CDS_LIB mstr_standard
J 0
(-5575 3975);
PAINT MONO (-5575 3975);
DISPLAY INVISIBLE (-5575 3975);
FORCEPROP 1 LAST BODY_TYPE PLUMBING
J 0
(-5575 3925);
DISPLAY 1.595745 (-5575 3925);
PAINT GREEN (-5575 3925);
DISPLAY INVISIBLE (-5575 3925);
FORCEPROP 1 LAST HDL_TAP TRUE
J 0
(-5250 3850);
DISPLAY 1.595745 (-5250 3850);
PAINT GREEN (-5250 3850);
DISPLAY INVISIBLE (-5250 3850);
FORCEPROP 1 LAST PATH I71
J 0
(-5577 3975);
DISPLAY 0.872340 (-5577 3975);
PAINT GREEN (-5577 3975);
DISPLAY INVISIBLE (-5577 3975);
FORCEADD OFFPAGE..6
(-6425 4800);
FORCEPROP 2 LAST $XR0 85 
J 0
(-6674 4800);
DISPLAY 0.638298 (-6674 4800);
PAINT MONO (-6674 4800);
FORCEPROP 2 LAST $XR1 86 
J 0
(-6764 4800);
DISPLAY 0.638298 (-6764 4800);
PAINT MONO (-6764 4800);
FORCEPROP 2 LAST CDS_LIB mstr_standard
J 0
(-6425 4800);
PAINT MONO (-6425 4800);
DISPLAY INVISIBLE (-6425 4800);
FORCEPROP 1 LAST OFFPAGE TRUE
J 0
(-6100 4675);
DISPLAY 1.170213 (-6100 4675);
PAINT GREEN (-6100 4675);
DISPLAY INVISIBLE (-6100 4675);
FORCEPROP 1 LAST COMMENT_BODY TRUE
J 0
(-6325 4725);
DISPLAY 1.170213 (-6325 4725);
PAINT GREEN (-6325 4725);
DISPLAY INVISIBLE (-6325 4725);
FORCEPROP 2 LAST PATH I72
J 0
(-6375 4875);
DISPLAY 1.021277 (-6375 4875);
PAINT ORANGE (-6375 4875);
DISPLAY INVISIBLE (-6375 4875);
FORCEADD TAP..6
(-5575 4025);
FORCEPROP 3 LASTPIN (-5525 4025) SIG_NAME M_L_DQ<50>
J 0
(-5515 4035);
DISPLAY 0.659574 (-5515 4035);
PAINT MONO (-5515 4035);
DISPLAY INVISIBLE (-5515 4035);
FORCEPROP 1 LASTPIN (-5525 4025) BN 50
J 0
(-5577 4033);
DISPLAY 0.617021 (-5577 4033);
PAINT GREEN (-5577 4033);
FORCEPROP 2 LAST CDS_LIB mstr_standard
J 0
(-5575 4025);
PAINT MONO (-5575 4025);
DISPLAY INVISIBLE (-5575 4025);
FORCEPROP 1 LAST BODY_TYPE PLUMBING
J 0
(-5575 3975);
DISPLAY 1.595745 (-5575 3975);
PAINT GREEN (-5575 3975);
DISPLAY INVISIBLE (-5575 3975);
FORCEPROP 1 LAST HDL_TAP TRUE
J 0
(-5250 3900);
DISPLAY 1.595745 (-5250 3900);
PAINT GREEN (-5250 3900);
DISPLAY INVISIBLE (-5250 3900);
FORCEPROP 1 LAST PATH I73
J 0
(-5577 4025);
DISPLAY 0.872340 (-5577 4025);
PAINT GREEN (-5577 4025);
DISPLAY INVISIBLE (-5577 4025);
FORCEADD TAP..6
(-5575 4075);
FORCEPROP 3 LASTPIN (-5525 4075) SIG_NAME M_L_DQ<51>
J 0
(-5515 4085);
DISPLAY 0.659574 (-5515 4085);
PAINT MONO (-5515 4085);
DISPLAY INVISIBLE (-5515 4085);
FORCEPROP 1 LASTPIN (-5525 4075) BN 51
J 0
(-5577 4083);
DISPLAY 0.617021 (-5577 4083);
PAINT GREEN (-5577 4083);
FORCEPROP 2 LAST CDS_LIB mstr_standard
J 0
(-5575 4075);
PAINT MONO (-5575 4075);
DISPLAY INVISIBLE (-5575 4075);
FORCEPROP 1 LAST BODY_TYPE PLUMBING
J 0
(-5575 4025);
DISPLAY 1.595745 (-5575 4025);
PAINT GREEN (-5575 4025);
DISPLAY INVISIBLE (-5575 4025);
FORCEPROP 1 LAST HDL_TAP TRUE
J 0
(-5250 3950);
DISPLAY 1.595745 (-5250 3950);
PAINT GREEN (-5250 3950);
DISPLAY INVISIBLE (-5250 3950);
FORCEPROP 1 LAST PATH I74
J 0
(-5577 4075);
DISPLAY 0.872340 (-5577 4075);
PAINT GREEN (-5577 4075);
DISPLAY INVISIBLE (-5577 4075);
FORCEADD TAP..6
(-5575 4125);
FORCEPROP 3 LASTPIN (-5525 4125) SIG_NAME M_L_DQ<52>
J 0
(-5515 4135);
DISPLAY 0.659574 (-5515 4135);
PAINT MONO (-5515 4135);
DISPLAY INVISIBLE (-5515 4135);
FORCEPROP 1 LASTPIN (-5525 4125) BN 52
J 0
(-5577 4133);
DISPLAY 0.617021 (-5577 4133);
PAINT GREEN (-5577 4133);
FORCEPROP 2 LAST CDS_LIB mstr_standard
J 0
(-5575 4125);
PAINT MONO (-5575 4125);
DISPLAY INVISIBLE (-5575 4125);
FORCEPROP 1 LAST BODY_TYPE PLUMBING
J 0
(-5575 4075);
DISPLAY 1.595745 (-5575 4075);
PAINT GREEN (-5575 4075);
DISPLAY INVISIBLE (-5575 4075);
FORCEPROP 1 LAST HDL_TAP TRUE
J 0
(-5250 4000);
DISPLAY 1.595745 (-5250 4000);
PAINT GREEN (-5250 4000);
DISPLAY INVISIBLE (-5250 4000);
FORCEPROP 1 LAST PATH I75
J 0
(-5577 4125);
DISPLAY 0.872340 (-5577 4125);
PAINT GREEN (-5577 4125);
DISPLAY INVISIBLE (-5577 4125);
FORCEADD TAP..6
(-5575 4175);
FORCEPROP 3 LASTPIN (-5525 4175) SIG_NAME M_L_DQ<53>
J 0
(-5515 4185);
DISPLAY 0.659574 (-5515 4185);
PAINT MONO (-5515 4185);
DISPLAY INVISIBLE (-5515 4185);
FORCEPROP 1 LASTPIN (-5525 4175) BN 53
J 0
(-5577 4183);
DISPLAY 0.617021 (-5577 4183);
PAINT GREEN (-5577 4183);
FORCEPROP 2 LAST CDS_LIB mstr_standard
J 0
(-5575 4175);
PAINT MONO (-5575 4175);
DISPLAY INVISIBLE (-5575 4175);
FORCEPROP 1 LAST BODY_TYPE PLUMBING
J 0
(-5575 4125);
DISPLAY 1.595745 (-5575 4125);
PAINT GREEN (-5575 4125);
DISPLAY INVISIBLE (-5575 4125);
FORCEPROP 1 LAST HDL_TAP TRUE
J 0
(-5250 4050);
DISPLAY 1.595745 (-5250 4050);
PAINT GREEN (-5250 4050);
DISPLAY INVISIBLE (-5250 4050);
FORCEPROP 1 LAST PATH I76
J 0
(-5577 4175);
DISPLAY 0.872340 (-5577 4175);
PAINT GREEN (-5577 4175);
DISPLAY INVISIBLE (-5577 4175);
FORCEADD TAP..6
(-5575 4225);
FORCEPROP 3 LASTPIN (-5525 4225) SIG_NAME M_L_DQ<54>
J 0
(-5515 4235);
DISPLAY 0.659574 (-5515 4235);
PAINT MONO (-5515 4235);
DISPLAY INVISIBLE (-5515 4235);
FORCEPROP 1 LASTPIN (-5525 4225) BN 54
J 0
(-5577 4233);
DISPLAY 0.617021 (-5577 4233);
PAINT GREEN (-5577 4233);
FORCEPROP 2 LAST CDS_LIB mstr_standard
J 0
(-5575 4225);
PAINT MONO (-5575 4225);
DISPLAY INVISIBLE (-5575 4225);
FORCEPROP 1 LAST BODY_TYPE PLUMBING
J 0
(-5575 4175);
DISPLAY 1.595745 (-5575 4175);
PAINT GREEN (-5575 4175);
DISPLAY INVISIBLE (-5575 4175);
FORCEPROP 1 LAST HDL_TAP TRUE
J 0
(-5250 4100);
DISPLAY 1.595745 (-5250 4100);
PAINT GREEN (-5250 4100);
DISPLAY INVISIBLE (-5250 4100);
FORCEPROP 1 LAST PATH I77
J 0
(-5577 4225);
DISPLAY 0.872340 (-5577 4225);
PAINT GREEN (-5577 4225);
DISPLAY INVISIBLE (-5577 4225);
FORCEADD TAP..6
(-5575 4275);
FORCEPROP 3 LASTPIN (-5525 4275) SIG_NAME M_L_DQ<55>
J 0
(-5515 4285);
DISPLAY 0.659574 (-5515 4285);
PAINT MONO (-5515 4285);
DISPLAY INVISIBLE (-5515 4285);
FORCEPROP 1 LASTPIN (-5525 4275) BN 55
J 0
(-5577 4283);
DISPLAY 0.617021 (-5577 4283);
PAINT GREEN (-5577 4283);
FORCEPROP 2 LAST CDS_LIB mstr_standard
J 0
(-5575 4275);
PAINT MONO (-5575 4275);
DISPLAY INVISIBLE (-5575 4275);
FORCEPROP 1 LAST BODY_TYPE PLUMBING
J 0
(-5575 4225);
DISPLAY 1.595745 (-5575 4225);
PAINT GREEN (-5575 4225);
DISPLAY INVISIBLE (-5575 4225);
FORCEPROP 1 LAST HDL_TAP TRUE
J 0
(-5250 4150);
DISPLAY 1.595745 (-5250 4150);
PAINT GREEN (-5250 4150);
DISPLAY INVISIBLE (-5250 4150);
FORCEPROP 1 LAST PATH I78
J 0
(-5577 4275);
DISPLAY 0.872340 (-5577 4275);
PAINT GREEN (-5577 4275);
DISPLAY INVISIBLE (-5577 4275);
FORCEADD TAP..6
(-5575 4325);
FORCEPROP 3 LASTPIN (-5525 4325) SIG_NAME M_L_DQ<56>
J 0
(-5515 4335);
DISPLAY 0.659574 (-5515 4335);
PAINT MONO (-5515 4335);
DISPLAY INVISIBLE (-5515 4335);
FORCEPROP 1 LASTPIN (-5525 4325) BN 56
J 0
(-5577 4333);
DISPLAY 0.617021 (-5577 4333);
PAINT GREEN (-5577 4333);
FORCEPROP 2 LAST CDS_LIB mstr_standard
J 0
(-5575 4325);
PAINT MONO (-5575 4325);
DISPLAY INVISIBLE (-5575 4325);
FORCEPROP 1 LAST BODY_TYPE PLUMBING
J 0
(-5575 4275);
DISPLAY 1.595745 (-5575 4275);
PAINT GREEN (-5575 4275);
DISPLAY INVISIBLE (-5575 4275);
FORCEPROP 1 LAST HDL_TAP TRUE
J 0
(-5250 4200);
DISPLAY 1.595745 (-5250 4200);
PAINT GREEN (-5250 4200);
DISPLAY INVISIBLE (-5250 4200);
FORCEPROP 1 LAST PATH I79
J 0
(-5577 4325);
DISPLAY 0.872340 (-5577 4325);
PAINT GREEN (-5577 4325);
DISPLAY INVISIBLE (-5577 4325);
FORCEADD TAP..6
(-5575 725);
FORCEPROP 3 LASTPIN (-5525 725) SIG_NAME M_L_CLK_DN<2>
J 0
(-5515 735);
DISPLAY 0.659574 (-5515 735);
PAINT MONO (-5515 735);
DISPLAY INVISIBLE (-5515 735);
FORCEPROP 1 LASTPIN (-5525 725) BN 2
J 0
(-5577 733);
DISPLAY 0.617021 (-5577 733);
PAINT GREEN (-5577 733);
FORCEPROP 2 LAST CDS_LIB mstr_standard
J 0
(-5575 725);
PAINT MONO (-5575 725);
DISPLAY INVISIBLE (-5575 725);
FORCEPROP 1 LAST BODY_TYPE PLUMBING
J 0
(-5575 675);
DISPLAY 1.595745 (-5575 675);
PAINT GREEN (-5575 675);
DISPLAY INVISIBLE (-5575 675);
FORCEPROP 1 LAST HDL_TAP TRUE
J 0
(-5250 600);
DISPLAY 1.595745 (-5250 600);
PAINT GREEN (-5250 600);
DISPLAY INVISIBLE (-5250 600);
FORCEPROP 1 LAST PATH I8
J 0
(-5577 725);
DISPLAY 0.872340 (-5577 725);
PAINT GREEN (-5577 725);
DISPLAY INVISIBLE (-5577 725);
FORCEADD TAP..6
(-5575 4375);
FORCEPROP 3 LASTPIN (-5525 4375) SIG_NAME M_L_DQ<57>
J 0
(-5515 4385);
DISPLAY 0.659574 (-5515 4385);
PAINT MONO (-5515 4385);
DISPLAY INVISIBLE (-5515 4385);
FORCEPROP 1 LASTPIN (-5525 4375) BN 57
J 0
(-5577 4383);
DISPLAY 0.617021 (-5577 4383);
PAINT GREEN (-5577 4383);
FORCEPROP 2 LAST CDS_LIB mstr_standard
J 0
(-5575 4375);
PAINT MONO (-5575 4375);
DISPLAY INVISIBLE (-5575 4375);
FORCEPROP 1 LAST BODY_TYPE PLUMBING
J 0
(-5575 4325);
DISPLAY 1.595745 (-5575 4325);
PAINT GREEN (-5575 4325);
DISPLAY INVISIBLE (-5575 4325);
FORCEPROP 1 LAST HDL_TAP TRUE
J 0
(-5250 4250);
DISPLAY 1.595745 (-5250 4250);
PAINT GREEN (-5250 4250);
DISPLAY INVISIBLE (-5250 4250);
FORCEPROP 1 LAST PATH I80
J 0
(-5577 4375);
DISPLAY 0.872340 (-5577 4375);
PAINT GREEN (-5577 4375);
DISPLAY INVISIBLE (-5577 4375);
FORCEADD TAP..6
(-5575 4425);
FORCEPROP 3 LASTPIN (-5525 4425) SIG_NAME M_L_DQ<58>
J 0
(-5515 4435);
DISPLAY 0.659574 (-5515 4435);
PAINT MONO (-5515 4435);
DISPLAY INVISIBLE (-5515 4435);
FORCEPROP 1 LASTPIN (-5525 4425) BN 58
J 0
(-5577 4433);
DISPLAY 0.617021 (-5577 4433);
PAINT GREEN (-5577 4433);
FORCEPROP 2 LAST CDS_LIB mstr_standard
J 0
(-5575 4425);
PAINT MONO (-5575 4425);
DISPLAY INVISIBLE (-5575 4425);
FORCEPROP 1 LAST BODY_TYPE PLUMBING
J 0
(-5575 4375);
DISPLAY 1.595745 (-5575 4375);
PAINT GREEN (-5575 4375);
DISPLAY INVISIBLE (-5575 4375);
FORCEPROP 1 LAST HDL_TAP TRUE
J 0
(-5250 4300);
DISPLAY 1.595745 (-5250 4300);
PAINT GREEN (-5250 4300);
DISPLAY INVISIBLE (-5250 4300);
FORCEPROP 1 LAST PATH I81
J 0
(-5577 4425);
DISPLAY 0.872340 (-5577 4425);
PAINT GREEN (-5577 4425);
DISPLAY INVISIBLE (-5577 4425);
FORCEADD TAP..6
(-5575 4475);
FORCEPROP 3 LASTPIN (-5525 4475) SIG_NAME M_L_DQ<59>
J 0
(-5515 4485);
DISPLAY 0.659574 (-5515 4485);
PAINT MONO (-5515 4485);
DISPLAY INVISIBLE (-5515 4485);
FORCEPROP 1 LASTPIN (-5525 4475) BN 59
J 0
(-5577 4483);
DISPLAY 0.617021 (-5577 4483);
PAINT GREEN (-5577 4483);
FORCEPROP 2 LAST CDS_LIB mstr_standard
J 0
(-5575 4475);
PAINT MONO (-5575 4475);
DISPLAY INVISIBLE (-5575 4475);
FORCEPROP 1 LAST BODY_TYPE PLUMBING
J 0
(-5575 4425);
DISPLAY 1.595745 (-5575 4425);
PAINT GREEN (-5575 4425);
DISPLAY INVISIBLE (-5575 4425);
FORCEPROP 1 LAST HDL_TAP TRUE
J 0
(-5250 4350);
DISPLAY 1.595745 (-5250 4350);
PAINT GREEN (-5250 4350);
DISPLAY INVISIBLE (-5250 4350);
FORCEPROP 1 LAST PATH I82
J 0
(-5577 4475);
DISPLAY 0.872340 (-5577 4475);
PAINT GREEN (-5577 4475);
DISPLAY INVISIBLE (-5577 4475);
FORCEADD TAP..6
(-5575 4525);
FORCEPROP 3 LASTPIN (-5525 4525) SIG_NAME M_L_DQ<60>
J 0
(-5515 4535);
DISPLAY 0.659574 (-5515 4535);
PAINT MONO (-5515 4535);
DISPLAY INVISIBLE (-5515 4535);
FORCEPROP 1 LASTPIN (-5525 4525) BN 60
J 0
(-5577 4533);
DISPLAY 0.617021 (-5577 4533);
PAINT GREEN (-5577 4533);
FORCEPROP 2 LAST CDS_LIB mstr_standard
J 0
(-5575 4525);
PAINT MONO (-5575 4525);
DISPLAY INVISIBLE (-5575 4525);
FORCEPROP 1 LAST BODY_TYPE PLUMBING
J 0
(-5575 4475);
DISPLAY 1.595745 (-5575 4475);
PAINT GREEN (-5575 4475);
DISPLAY INVISIBLE (-5575 4475);
FORCEPROP 1 LAST HDL_TAP TRUE
J 0
(-5250 4400);
DISPLAY 1.595745 (-5250 4400);
PAINT GREEN (-5250 4400);
DISPLAY INVISIBLE (-5250 4400);
FORCEPROP 1 LAST PATH I83
J 0
(-5577 4525);
DISPLAY 0.872340 (-5577 4525);
PAINT GREEN (-5577 4525);
DISPLAY INVISIBLE (-5577 4525);
FORCEADD TAP..6
(-5575 4575);
FORCEPROP 3 LASTPIN (-5525 4575) SIG_NAME M_L_DQ<61>
J 0
(-5515 4585);
DISPLAY 0.659574 (-5515 4585);
PAINT MONO (-5515 4585);
DISPLAY INVISIBLE (-5515 4585);
FORCEPROP 1 LASTPIN (-5525 4575) BN 61
J 0
(-5577 4583);
DISPLAY 0.617021 (-5577 4583);
PAINT GREEN (-5577 4583);
FORCEPROP 2 LAST CDS_LIB mstr_standard
J 0
(-5575 4575);
PAINT MONO (-5575 4575);
DISPLAY INVISIBLE (-5575 4575);
FORCEPROP 1 LAST BODY_TYPE PLUMBING
J 0
(-5575 4525);
DISPLAY 1.595745 (-5575 4525);
PAINT GREEN (-5575 4525);
DISPLAY INVISIBLE (-5575 4525);
FORCEPROP 1 LAST HDL_TAP TRUE
J 0
(-5250 4450);
DISPLAY 1.595745 (-5250 4450);
PAINT GREEN (-5250 4450);
DISPLAY INVISIBLE (-5250 4450);
FORCEPROP 1 LAST PATH I84
J 0
(-5577 4575);
DISPLAY 0.872340 (-5577 4575);
PAINT GREEN (-5577 4575);
DISPLAY INVISIBLE (-5577 4575);
FORCEADD TAP..6
(-5575 4625);
FORCEPROP 3 LASTPIN (-5525 4625) SIG_NAME M_L_DQ<62>
J 0
(-5515 4635);
DISPLAY 0.659574 (-5515 4635);
PAINT MONO (-5515 4635);
DISPLAY INVISIBLE (-5515 4635);
FORCEPROP 1 LASTPIN (-5525 4625) BN 62
J 0
(-5577 4633);
DISPLAY 0.617021 (-5577 4633);
PAINT GREEN (-5577 4633);
FORCEPROP 2 LAST CDS_LIB mstr_standard
J 0
(-5575 4625);
PAINT MONO (-5575 4625);
DISPLAY INVISIBLE (-5575 4625);
FORCEPROP 1 LAST BODY_TYPE PLUMBING
J 0
(-5575 4575);
DISPLAY 1.595745 (-5575 4575);
PAINT GREEN (-5575 4575);
DISPLAY INVISIBLE (-5575 4575);
FORCEPROP 1 LAST HDL_TAP TRUE
J 0
(-5250 4500);
DISPLAY 1.595745 (-5250 4500);
PAINT GREEN (-5250 4500);
DISPLAY INVISIBLE (-5250 4500);
FORCEPROP 1 LAST PATH I85
J 0
(-5577 4625);
DISPLAY 0.872340 (-5577 4625);
PAINT GREEN (-5577 4625);
DISPLAY INVISIBLE (-5577 4625);
FORCEADD TAP..6
(-5575 4675);
FORCEPROP 3 LASTPIN (-5525 4675) SIG_NAME M_L_DQ<63>
J 0
(-5515 4685);
DISPLAY 0.659574 (-5515 4685);
PAINT MONO (-5515 4685);
DISPLAY INVISIBLE (-5515 4685);
FORCEPROP 1 LASTPIN (-5525 4675) BN 63
J 0
(-5577 4683);
DISPLAY 0.617021 (-5577 4683);
PAINT GREEN (-5577 4683);
FORCEPROP 2 LAST CDS_LIB mstr_standard
J 0
(-5575 4675);
PAINT MONO (-5575 4675);
DISPLAY INVISIBLE (-5575 4675);
FORCEPROP 1 LAST BODY_TYPE PLUMBING
J 0
(-5575 4625);
DISPLAY 1.595745 (-5575 4625);
PAINT GREEN (-5575 4625);
DISPLAY INVISIBLE (-5575 4625);
FORCEPROP 1 LAST HDL_TAP TRUE
J 0
(-5250 4550);
DISPLAY 1.595745 (-5250 4550);
PAINT GREEN (-5250 4550);
DISPLAY INVISIBLE (-5250 4550);
FORCEPROP 1 LAST PATH I86
J 0
(-5577 4675);
DISPLAY 0.872340 (-5577 4675);
PAINT GREEN (-5577 4675);
DISPLAY INVISIBLE (-5577 4675);
FORCEADD TAP..6
R 2
(-2850 775);
FORCEPROP 3 LASTPIN (-2900 775) SIG_NAME M_L_BA<1>
J 0
(-2890 785);
DISPLAY 0.659574 (-2890 785);
PAINT MONO (-2890 785);
DISPLAY INVISIBLE (-2890 785);
FORCEPROP 1 LASTPIN (-2900 775) BN 1
J 2
(-2848 783);
DISPLAY 0.617021 (-2848 783);
PAINT GREEN (-2848 783);
FORCEPROP 2 LAST CDS_LIB mstr_standard
J 0
(-2850 775);
PAINT MONO (-2850 775);
DISPLAY INVISIBLE (-2850 775);
FORCEPROP 1 LAST BODY_TYPE PLUMBING
J 2
(-2850 725);
DISPLAY 1.595745 (-2850 725);
PAINT GREEN (-2850 725);
DISPLAY INVISIBLE (-2850 725);
FORCEPROP 1 LAST HDL_TAP TRUE
J 2
(-3175 650);
DISPLAY 1.595745 (-3175 650);
PAINT GREEN (-3175 650);
DISPLAY INVISIBLE (-3175 650);
FORCEPROP 1 LAST PATH I87
J 2
(-2848 775);
DISPLAY 0.872340 (-2848 775);
PAINT GREEN (-2848 775);
DISPLAY INVISIBLE (-2848 775);
FORCEADD TAP..6
R 2
(-2850 725);
FORCEPROP 3 LASTPIN (-2900 725) SIG_NAME M_L_BA<0>
J 0
(-2890 735);
DISPLAY 0.659574 (-2890 735);
PAINT MONO (-2890 735);
DISPLAY INVISIBLE (-2890 735);
FORCEPROP 1 LASTPIN (-2900 725) BN 0
J 2
(-2848 733);
DISPLAY 0.617021 (-2848 733);
PAINT GREEN (-2848 733);
FORCEPROP 2 LAST CDS_LIB mstr_standard
J 0
(-2850 725);
PAINT MONO (-2850 725);
DISPLAY INVISIBLE (-2850 725);
FORCEPROP 1 LAST BODY_TYPE PLUMBING
J 2
(-2850 675);
DISPLAY 1.595745 (-2850 675);
PAINT GREEN (-2850 675);
DISPLAY INVISIBLE (-2850 675);
FORCEPROP 1 LAST HDL_TAP TRUE
J 2
(-3175 600);
DISPLAY 1.595745 (-3175 600);
PAINT GREEN (-3175 600);
DISPLAY INVISIBLE (-3175 600);
FORCEPROP 1 LAST PATH I88
J 2
(-2848 725);
DISPLAY 0.872340 (-2848 725);
PAINT GREEN (-2848 725);
DISPLAY INVISIBLE (-2848 725);
FORCEADD TAP..6
R 2
(-2850 825);
FORCEPROP 3 LASTPIN (-2900 825) SIG_NAME M_L_BG<0>
J 0
(-2890 835);
DISPLAY 0.659574 (-2890 835);
PAINT MONO (-2890 835);
DISPLAY INVISIBLE (-2890 835);
FORCEPROP 1 LASTPIN (-2900 825) BN 0
J 2
(-2848 833);
DISPLAY 0.617021 (-2848 833);
PAINT GREEN (-2848 833);
FORCEPROP 2 LAST CDS_LIB mstr_standard
J 0
(-2850 825);
PAINT MONO (-2850 825);
DISPLAY INVISIBLE (-2850 825);
FORCEPROP 1 LAST BODY_TYPE PLUMBING
J 2
(-2850 775);
DISPLAY 1.595745 (-2850 775);
PAINT GREEN (-2850 775);
DISPLAY INVISIBLE (-2850 775);
FORCEPROP 1 LAST HDL_TAP TRUE
J 2
(-3175 700);
DISPLAY 1.595745 (-3175 700);
PAINT GREEN (-3175 700);
DISPLAY INVISIBLE (-3175 700);
FORCEPROP 1 LAST PATH I89
J 2
(-2848 825);
DISPLAY 0.872340 (-2848 825);
PAINT GREEN (-2848 825);
DISPLAY INVISIBLE (-2848 825);
FORCEADD TAP..6
(-5575 875);
FORCEPROP 3 LASTPIN (-5525 875) SIG_NAME M_L_CLK_DP<1>
J 0
(-5515 885);
DISPLAY 0.659574 (-5515 885);
PAINT MONO (-5515 885);
DISPLAY INVISIBLE (-5515 885);
FORCEPROP 1 LASTPIN (-5525 875) BN 1
J 0
(-5577 883);
DISPLAY 0.617021 (-5577 883);
PAINT GREEN (-5577 883);
FORCEPROP 2 LAST CDS_LIB mstr_standard
J 0
(-5575 875);
PAINT MONO (-5575 875);
DISPLAY INVISIBLE (-5575 875);
FORCEPROP 1 LAST BODY_TYPE PLUMBING
J 0
(-5575 825);
DISPLAY 1.595745 (-5575 825);
PAINT GREEN (-5575 825);
DISPLAY INVISIBLE (-5575 825);
FORCEPROP 1 LAST HDL_TAP TRUE
J 0
(-5250 750);
DISPLAY 1.595745 (-5250 750);
PAINT GREEN (-5250 750);
DISPLAY INVISIBLE (-5250 750);
FORCEPROP 1 LAST PATH I9
J 0
(-5577 875);
DISPLAY 0.872340 (-5577 875);
PAINT GREEN (-5577 875);
DISPLAY INVISIBLE (-5577 875);
FORCEADD TAP..6
R 2
(-2850 875);
FORCEPROP 3 LASTPIN (-2900 875) SIG_NAME M_L_BG<1>
J 0
(-2890 885);
DISPLAY 0.659574 (-2890 885);
PAINT MONO (-2890 885);
DISPLAY INVISIBLE (-2890 885);
FORCEPROP 1 LASTPIN (-2900 875) BN 1
J 2
(-2848 883);
DISPLAY 0.617021 (-2848 883);
PAINT GREEN (-2848 883);
FORCEPROP 2 LAST CDS_LIB mstr_standard
J 0
(-2850 875);
PAINT MONO (-2850 875);
DISPLAY INVISIBLE (-2850 875);
FORCEPROP 1 LAST BODY_TYPE PLUMBING
J 2
(-2850 825);
DISPLAY 1.595745 (-2850 825);
PAINT GREEN (-2850 825);
DISPLAY INVISIBLE (-2850 825);
FORCEPROP 1 LAST HDL_TAP TRUE
J 2
(-3175 750);
DISPLAY 1.595745 (-3175 750);
PAINT GREEN (-3175 750);
DISPLAY INVISIBLE (-3175 750);
FORCEPROP 1 LAST PATH I90
J 2
(-2848 875);
DISPLAY 0.872340 (-2848 875);
PAINT GREEN (-2848 875);
DISPLAY INVISIBLE (-2848 875);
FORCEADD TAP..6
R 2
(-2850 1075);
FORCEPROP 3 LASTPIN (-2900 1075) SIG_NAME M_L_CS_N<2>
J 0
(-2890 1085);
DISPLAY 0.659574 (-2890 1085);
PAINT MONO (-2890 1085);
DISPLAY INVISIBLE (-2890 1085);
FORCEPROP 1 LASTPIN (-2900 1075) BN 2
J 2
(-2848 1083);
DISPLAY 0.617021 (-2848 1083);
PAINT GREEN (-2848 1083);
FORCEPROP 2 LAST CDS_LIB mstr_standard
J 0
(-2850 1075);
PAINT MONO (-2850 1075);
DISPLAY INVISIBLE (-2850 1075);
FORCEPROP 1 LAST BODY_TYPE PLUMBING
J 2
(-2850 1025);
DISPLAY 1.595745 (-2850 1025);
PAINT GREEN (-2850 1025);
DISPLAY INVISIBLE (-2850 1025);
FORCEPROP 1 LAST HDL_TAP TRUE
J 2
(-3175 950);
DISPLAY 1.595745 (-3175 950);
PAINT GREEN (-3175 950);
DISPLAY INVISIBLE (-3175 950);
FORCEPROP 1 LAST PATH I91
J 2
(-2848 1075);
DISPLAY 0.872340 (-2848 1075);
PAINT GREEN (-2848 1075);
DISPLAY INVISIBLE (-2848 1075);
FORCEADD TAP..6
R 2
(-2850 1025);
FORCEPROP 3 LASTPIN (-2900 1025) SIG_NAME M_L_CS_N<1>
J 0
(-2890 1035);
DISPLAY 0.659574 (-2890 1035);
PAINT MONO (-2890 1035);
DISPLAY INVISIBLE (-2890 1035);
FORCEPROP 1 LASTPIN (-2900 1025) BN 1
J 2
(-2848 1033);
DISPLAY 0.617021 (-2848 1033);
PAINT GREEN (-2848 1033);
FORCEPROP 2 LAST CDS_LIB mstr_standard
J 0
(-2850 1025);
PAINT MONO (-2850 1025);
DISPLAY INVISIBLE (-2850 1025);
FORCEPROP 1 LAST BODY_TYPE PLUMBING
J 2
(-2850 975);
DISPLAY 1.595745 (-2850 975);
PAINT GREEN (-2850 975);
DISPLAY INVISIBLE (-2850 975);
FORCEPROP 1 LAST HDL_TAP TRUE
J 2
(-3175 900);
DISPLAY 1.595745 (-3175 900);
PAINT GREEN (-3175 900);
DISPLAY INVISIBLE (-3175 900);
FORCEPROP 1 LAST PATH I92
J 2
(-2848 1025);
DISPLAY 0.872340 (-2848 1025);
PAINT GREEN (-2848 1025);
DISPLAY INVISIBLE (-2848 1025);
FORCEADD TAP..6
R 2
(-2850 975);
FORCEPROP 3 LASTPIN (-2900 975) SIG_NAME M_L_CS_N<0>
J 0
(-2890 985);
DISPLAY 0.659574 (-2890 985);
PAINT MONO (-2890 985);
DISPLAY INVISIBLE (-2890 985);
FORCEPROP 1 LASTPIN (-2900 975) BN 0
J 2
(-2848 983);
DISPLAY 0.617021 (-2848 983);
PAINT GREEN (-2848 983);
FORCEPROP 2 LAST CDS_LIB mstr_standard
J 0
(-2850 975);
PAINT MONO (-2850 975);
DISPLAY INVISIBLE (-2850 975);
FORCEPROP 1 LAST BODY_TYPE PLUMBING
J 2
(-2850 925);
DISPLAY 1.595745 (-2850 925);
PAINT GREEN (-2850 925);
DISPLAY INVISIBLE (-2850 925);
FORCEPROP 1 LAST HDL_TAP TRUE
J 2
(-3175 850);
DISPLAY 1.595745 (-3175 850);
PAINT GREEN (-3175 850);
DISPLAY INVISIBLE (-3175 850);
FORCEPROP 1 LAST PATH I93
J 2
(-2848 975);
DISPLAY 0.872340 (-2848 975);
PAINT GREEN (-2848 975);
DISPLAY INVISIBLE (-2848 975);
FORCEADD TAP..6
R 2
(-2850 1175);
FORCEPROP 3 LASTPIN (-2900 1175) SIG_NAME M_L_CS_N<4>
J 0
(-2890 1185);
DISPLAY 0.659574 (-2890 1185);
PAINT MONO (-2890 1185);
DISPLAY INVISIBLE (-2890 1185);
FORCEPROP 1 LASTPIN (-2900 1175) BN 4
J 2
(-2848 1183);
DISPLAY 0.617021 (-2848 1183);
PAINT GREEN (-2848 1183);
FORCEPROP 2 LAST CDS_LIB mstr_standard
J 0
(-2850 1175);
PAINT MONO (-2850 1175);
DISPLAY INVISIBLE (-2850 1175);
FORCEPROP 1 LAST BODY_TYPE PLUMBING
J 2
(-2850 1125);
DISPLAY 1.595745 (-2850 1125);
PAINT GREEN (-2850 1125);
DISPLAY INVISIBLE (-2850 1125);
FORCEPROP 1 LAST HDL_TAP TRUE
J 2
(-3175 1050);
DISPLAY 1.595745 (-3175 1050);
PAINT GREEN (-3175 1050);
DISPLAY INVISIBLE (-3175 1050);
FORCEPROP 1 LAST PATH I94
J 2
(-2848 1175);
DISPLAY 0.872340 (-2848 1175);
PAINT GREEN (-2848 1175);
DISPLAY INVISIBLE (-2848 1175);
FORCEADD TAP..6
R 2
(-2850 1125);
FORCEPROP 3 LASTPIN (-2900 1125) SIG_NAME M_L_CS_N<3>
J 0
(-2890 1135);
DISPLAY 0.659574 (-2890 1135);
PAINT MONO (-2890 1135);
DISPLAY INVISIBLE (-2890 1135);
FORCEPROP 1 LASTPIN (-2900 1125) BN 3
J 2
(-2848 1133);
DISPLAY 0.617021 (-2848 1133);
PAINT GREEN (-2848 1133);
FORCEPROP 2 LAST CDS_LIB mstr_standard
J 0
(-2850 1125);
PAINT MONO (-2850 1125);
DISPLAY INVISIBLE (-2850 1125);
FORCEPROP 1 LAST BODY_TYPE PLUMBING
J 2
(-2850 1075);
DISPLAY 1.595745 (-2850 1075);
PAINT GREEN (-2850 1075);
DISPLAY INVISIBLE (-2850 1075);
FORCEPROP 1 LAST HDL_TAP TRUE
J 2
(-3175 1000);
DISPLAY 1.595745 (-3175 1000);
PAINT GREEN (-3175 1000);
DISPLAY INVISIBLE (-3175 1000);
FORCEPROP 1 LAST PATH I95
J 2
(-2848 1125);
DISPLAY 0.872340 (-2848 1125);
PAINT GREEN (-2848 1125);
DISPLAY INVISIBLE (-2848 1125);
FORCEADD TAP..6
R 2
(-2850 1225);
FORCEPROP 3 LASTPIN (-2900 1225) SIG_NAME M_L_CS_N<5>
J 0
(-2890 1235);
DISPLAY 0.659574 (-2890 1235);
PAINT MONO (-2890 1235);
DISPLAY INVISIBLE (-2890 1235);
FORCEPROP 1 LASTPIN (-2900 1225) BN 5
J 2
(-2848 1233);
DISPLAY 0.617021 (-2848 1233);
PAINT GREEN (-2848 1233);
FORCEPROP 2 LAST CDS_LIB mstr_standard
J 0
(-2850 1225);
PAINT MONO (-2850 1225);
DISPLAY INVISIBLE (-2850 1225);
FORCEPROP 1 LAST BODY_TYPE PLUMBING
J 2
(-2850 1175);
DISPLAY 1.595745 (-2850 1175);
PAINT GREEN (-2850 1175);
DISPLAY INVISIBLE (-2850 1175);
FORCEPROP 1 LAST HDL_TAP TRUE
J 2
(-3175 1100);
DISPLAY 1.595745 (-3175 1100);
PAINT GREEN (-3175 1100);
DISPLAY INVISIBLE (-3175 1100);
FORCEPROP 1 LAST PATH I96
J 2
(-2848 1225);
DISPLAY 0.872340 (-2848 1225);
PAINT GREEN (-2848 1225);
DISPLAY INVISIBLE (-2848 1225);
FORCEADD TAP..6
R 2
(-2850 1275);
FORCEPROP 3 LASTPIN (-2900 1275) SIG_NAME M_L_CS_N<6>
J 0
(-2890 1285);
DISPLAY 0.659574 (-2890 1285);
PAINT MONO (-2890 1285);
DISPLAY INVISIBLE (-2890 1285);
FORCEPROP 1 LASTPIN (-2900 1275) BN 6
J 2
(-2848 1283);
DISPLAY 0.617021 (-2848 1283);
PAINT GREEN (-2848 1283);
FORCEPROP 2 LAST CDS_LIB mstr_standard
J 0
(-2850 1275);
PAINT MONO (-2850 1275);
DISPLAY INVISIBLE (-2850 1275);
FORCEPROP 1 LAST BODY_TYPE PLUMBING
J 2
(-2850 1225);
DISPLAY 1.595745 (-2850 1225);
PAINT GREEN (-2850 1225);
DISPLAY INVISIBLE (-2850 1225);
FORCEPROP 1 LAST HDL_TAP TRUE
J 2
(-3175 1150);
DISPLAY 1.595745 (-3175 1150);
PAINT GREEN (-3175 1150);
DISPLAY INVISIBLE (-3175 1150);
FORCEPROP 1 LAST PATH I97
J 2
(-2848 1275);
DISPLAY 0.872340 (-2848 1275);
PAINT GREEN (-2848 1275);
DISPLAY INVISIBLE (-2848 1275);
FORCEADD TAP..6
R 2
(-2850 1325);
FORCEPROP 3 LASTPIN (-2900 1325) SIG_NAME M_L_CS_N<7>
J 0
(-2890 1335);
DISPLAY 0.659574 (-2890 1335);
PAINT MONO (-2890 1335);
DISPLAY INVISIBLE (-2890 1335);
FORCEPROP 1 LASTPIN (-2900 1325) BN 7
J 2
(-2848 1333);
DISPLAY 0.617021 (-2848 1333);
PAINT GREEN (-2848 1333);
FORCEPROP 2 LAST CDS_LIB mstr_standard
J 0
(-2850 1325);
PAINT MONO (-2850 1325);
DISPLAY INVISIBLE (-2850 1325);
FORCEPROP 1 LAST BODY_TYPE PLUMBING
J 2
(-2850 1275);
DISPLAY 1.595745 (-2850 1275);
PAINT GREEN (-2850 1275);
DISPLAY INVISIBLE (-2850 1275);
FORCEPROP 1 LAST HDL_TAP TRUE
J 2
(-3175 1200);
DISPLAY 1.595745 (-3175 1200);
PAINT GREEN (-3175 1200);
DISPLAY INVISIBLE (-3175 1200);
FORCEPROP 1 LAST PATH I98
J 2
(-2848 1325);
DISPLAY 0.872340 (-2848 1325);
PAINT GREEN (-2848 1325);
DISPLAY INVISIBLE (-2848 1325);
FORCEADD TAP..6
R 2
(-2850 1425);
FORCEPROP 3 LASTPIN (-2900 1425) SIG_NAME M_L_ODT<0>
J 0
(-2890 1435);
DISPLAY 0.659574 (-2890 1435);
PAINT MONO (-2890 1435);
DISPLAY INVISIBLE (-2890 1435);
FORCEPROP 1 LASTPIN (-2900 1425) BN 0
J 2
(-2848 1433);
DISPLAY 0.617021 (-2848 1433);
PAINT GREEN (-2848 1433);
FORCEPROP 2 LAST CDS_LIB mstr_standard
J 0
(-2850 1425);
PAINT MONO (-2850 1425);
DISPLAY INVISIBLE (-2850 1425);
FORCEPROP 1 LAST BODY_TYPE PLUMBING
J 2
(-2850 1375);
DISPLAY 1.595745 (-2850 1375);
PAINT GREEN (-2850 1375);
DISPLAY INVISIBLE (-2850 1375);
FORCEPROP 1 LAST HDL_TAP TRUE
J 2
(-3175 1300);
DISPLAY 1.595745 (-3175 1300);
PAINT GREEN (-3175 1300);
DISPLAY INVISIBLE (-3175 1300);
FORCEPROP 1 LAST PATH I99
J 2
(-2848 1425);
DISPLAY 0.872340 (-2848 1425);
PAINT GREEN (-2848 1425);
DISPLAY INVISIBLE (-2848 1425);
FORCEADD DESIGN_NOTE..1
(-6400 400);
FORCEPROP 0 LAST L1 CPU SYMBOLS 1-30 ARE PRELIMINARY AND SUBJECT TO CHANGE
J 0
(-6600 275);
DISPLAY 1.021277 (-6600 275);
PAINT ORANGE (-6600 275);
FORCEPROP 2 LAST CDS_LIB mstr_symbols
J 0
(-6400 400);
PAINT ORANGE (-6400 400);
DISPLAY INVISIBLE (-6400 400);
FORCEPROP 1 LAST COMMENT_BODY TRUE
J 0
(-6375 500);
DISPLAY 0.978723 (-6375 500);
PAINT ORANGE (-6375 500);
DISPLAY INVISIBLE (-6375 500);
FORCEADD PRELIM..10
(-4215 2565);
PAINT GRAY (-4215 2565);
FORCEPROP 2 LAST CDS_LIB mstr_misc
J 0
(-4215 2565);
PAINT ORANGE (-4215 2565);
DISPLAY INVISIBLE (-4215 2565);
FORCEPROP 1 LAST COMMENT_BODY TRUE
J 0
(-4215 2565);
PAINT ORANGE (-4215 2565);
DISPLAY INVISIBLE (-4215 2565);
FORCEADD INTEL_CORP_BPAGE..1
(0 0);
FORCEPROP 1 LAST CDS_CON_LAST_MODIFIED Tue Dec 01 11:51:35 2015
J 0
(-1425 325);
DISPLAY 1.340426 (-1425 325);
PAINT GREEN (-1425 325);
DISPLAY INVISIBLE (-1425 325);
FORCEPROP 1 LAST CUSTOM_TXT_CDS <CURRENT_DESIGN_SHEET> OF <TOTAL_DESIGN_SHEETS>
J 0
(-500 25);
PAINT GREEN (-500 25);
FORCEPROP 1 LAST CUSTOM_TXT_CDS <CON_LAST_MODIFIED>
J 0
(-1925 350);
PAINT GREEN (-1925 350);
FORCEPROP 2 LAST CUSTOM_TXT_CDS <XR_PAGE_TITLE>
J 0
(-7890 5250);
DISPLAY 0.638298 (-7890 5250);
PAINT PINK (-7890 5250);
DISPLAY INVISIBLE (-7890 5250);
FORCEPROP 1 LAST SCH_ADDRESS3 Santa Clara, CA 95052-8119
J 0
(-3975 25);
DISPLAY 0.617021 (-3975 25);
PAINT GREEN (-3975 25);
FORCEPROP 1 LAST SCH_ADDRESS2 P.O. BOX 58119
J 0
(-3975 75);
DISPLAY 0.617021 (-3975 75);
PAINT GREEN (-3975 75);
FORCEPROP 1 LAST SCH_ADDRESS1 2200 Mission College Blvd.
J 0
(-3975 125);
DISPLAY 0.617021 (-3975 125);
PAINT GREEN (-3975 125);
FORCEPROP 1 LAST SCH_TITLE SKYLAKE - SKT1 - 7 OF 21
J 0
(-7950 50);
DISPLAY 1.212766 (-7950 50);
PAINT GREEN (-7950 50);
FORCEPROP 1 LAST SCH_NUMBER H4694802
J 0
(-1300 150);
DISPLAY 1.212766 (-1300 150);
PAINT YELLOW (-1300 150);
FORCEPROP 1 LAST SCH_DEPT BESD
J 1
(-4450 100);
DISPLAY 1.212766 (-4450 100);
PAINT YELLOW (-4450 100);
FORCEPROP 1 LAST SCH_REV 2.420
J 0
(-250 150);
DISPLAY 0.978723 (-250 150);
PAINT YELLOW (-250 150);
FORCEPROP 2 LAST PAGE_BORDER TRUE
J 0
(-7890 5250);
DISPLAY 0.851064 (-7890 5250);
PAINT PINK (-7890 5250);
DISPLAY INVISIBLE (-7890 5250);
FORCEPROP 2 LAST CDS_LIB mstr_symbols
J 0
(0 0);
PAINT ORANGE (0 0);
DISPLAY INVISIBLE (0 0);
FORCEPROP 1 LAST COMMENT_BODY TRUE
J 0
(12 12);
DISPLAY 0.638298 (12 12);
PAINT GREEN (12 12);
DISPLAY INVISIBLE (12 12);
FORCEPROP 2 LAST CDS_XR_PAGE_TITLE CR-61 : @BASEBOARD_FAB2_LIB.BASEBOARD_FAB2(SCH_1):PAGE61
J 0
(-7890 5250);
DISPLAY 0.638298 (-7890 5250);
PAINT PINK (-7890 5250);
DISPLAY INVISIBLE (-7890 5250);
WIRE 17 -1 (-2800 4700)(-2800 4750);
WIRE 17 -1 (-2800 4650)(-2800 4700);
WIRE 17 -1 (-2050 4750)(-2800 4750);
FORCEPROP 2 LAST SIG_NAME M_L_DQS_DP<17:0>
J 0
(-2700 4760);
DISPLAY 0.617021 (-2700 4760);
PAINT ORANGE (-2700 4760);
WIRE 17 -1 (-2800 4600)(-2800 4650);
WIRE 17 -1 (-2800 4550)(-2800 4600);
WIRE 17 -1 (-2800 4500)(-2800 4550);
WIRE 17 -1 (-2800 4450)(-2800 4500);
WIRE 17 -1 (-2800 4400)(-2800 4450);
WIRE 17 -1 (-2800 4350)(-2800 4400);
WIRE 17 -1 (-2800 4300)(-2800 4350);
WIRE 17 -1 (-2800 4250)(-2800 4300);
WIRE 17 -1 (-2800 4200)(-2800 4250);
WIRE 17 -1 (-2800 4150)(-2800 4200);
WIRE 17 -1 (-2800 4100)(-2800 4150);
WIRE 17 -1 (-2800 4050)(-2800 4100);
WIRE 17 -1 (-2800 4000)(-2800 4050);
WIRE 17 -1 (-2800 3950)(-2800 4000);
WIRE 17 -1 (-2800 3900)(-2800 3950);
WIRE 17 -1 (-2800 3850)(-2800 3900);
WIRE 17 -1 (-2800 3750)(-2800 3775);
WIRE 17 -1 (-2800 3700)(-2800 3750);
WIRE 17 -1 (-2050 3775)(-2800 3775);
FORCEPROP 2 LAST SIG_NAME M_L_DQS_DN<17:0>
J 0
(-2700 3785);
DISPLAY 0.617021 (-2700 3785);
PAINT ORANGE (-2700 3785);
WIRE 17 -1 (-2800 3650)(-2800 3700);
WIRE 17 -1 (-2800 3600)(-2800 3650);
WIRE 17 -1 (-2800 3550)(-2800 3600);
WIRE 17 -1 (-2800 3500)(-2800 3550);
WIRE 17 -1 (-2800 3450)(-2800 3500);
WIRE 17 -1 (-2800 3400)(-2800 3450);
WIRE 17 -1 (-2800 3350)(-2800 3400);
WIRE 17 -1 (-2800 3300)(-2800 3350);
WIRE 17 -1 (-2800 3250)(-2800 3300);
WIRE 17 -1 (-2800 3200)(-2800 3250);
WIRE 17 -1 (-2800 3150)(-2800 3200);
WIRE 17 -1 (-2800 3100)(-2800 3150);
WIRE 17 -1 (-2800 3050)(-2800 3100);
WIRE 17 -1 (-2800 3000)(-2800 3050);
WIRE 17 -1 (-2800 2950)(-2800 3000);
WIRE 17 -1 (-2800 2900)(-2800 2950);
WIRE 17 -1 (-2800 2800)(-2800 2825);
WIRE 17 -1 (-2800 2750)(-2800 2800);
WIRE 17 -1 (-2050 2825)(-2800 2825);
FORCEPROP 2 LAST SIG_NAME M_L_MA<17:0>
J 0
(-2700 2835);
DISPLAY 0.617021 (-2700 2835);
PAINT ORANGE (-2700 2835);
WIRE 17 -1 (-2800 2700)(-2800 2750);
WIRE 17 -1 (-2800 2650)(-2800 2700);
WIRE 17 -1 (-2800 2600)(-2800 2650);
WIRE 17 -1 (-2800 2550)(-2800 2600);
WIRE 17 -1 (-2800 2500)(-2800 2550);
WIRE 17 -1 (-2800 2450)(-2800 2500);
WIRE 17 -1 (-2800 2400)(-2800 2450);
WIRE 17 -1 (-2800 2350)(-2800 2400);
WIRE 17 -1 (-2800 2300)(-2800 2350);
WIRE 17 -1 (-2800 2250)(-2800 2300);
WIRE 17 -1 (-2800 2200)(-2800 2250);
WIRE 17 -1 (-2800 2150)(-2800 2200);
WIRE 17 -1 (-2800 2100)(-2800 2150);
WIRE 17 -1 (-2800 2050)(-2800 2100);
WIRE 17 -1 (-2800 2000)(-2800 2050);
WIRE 17 -1 (-2800 1950)(-2800 2000);
WIRE 17 -1 (-2800 800)(-2800 825);
WIRE 17 -1 (-2800 750)(-2800 800);
WIRE 17 -1 (-2050 825)(-2800 825);
FORCEPROP 2 LAST SIG_NAME M_L_BA<1:0>
J 0
(-2700 835);
DISPLAY 0.617021 (-2700 835);
PAINT ORANGE (-2700 835);
WIRE 17 -1 (-2800 850)(-2800 900);
WIRE 17 -1 (-2800 900)(-2800 925);
WIRE 17 -1 (-2050 925)(-2800 925);
FORCEPROP 2 LAST SIG_NAME M_L_BG<1:0>
J 0
(-2700 935);
DISPLAY 0.617021 (-2700 935);
PAINT ORANGE (-2700 935);
WIRE 17 -1 (-2800 1850)(-2800 1875);
WIRE 17 -1 (-2800 1800)(-2800 1850);
WIRE 17 -1 (-2050 1875)(-2800 1875);
FORCEPROP 2 LAST SIG_NAME M_L_CKE<3:0>
J 0
(-2700 1885);
DISPLAY 0.617021 (-2700 1885);
PAINT ORANGE (-2700 1885);
WIRE 17 -1 (-2800 1750)(-2800 1800);
WIRE 17 -1 (-2800 1700)(-2800 1750);
WIRE 17 -1 (-2800 1350)(-2800 1375);
WIRE 17 -1 (-2800 1300)(-2800 1350);
WIRE 17 -1 (-2050 1375)(-2800 1375);
FORCEPROP 2 LAST SIG_NAME M_L_CS_N<7:0>
J 0
(-2700 1385);
DISPLAY 0.617021 (-2700 1385);
PAINT ORANGE (-2700 1385);
WIRE 17 -1 (-2800 1250)(-2800 1300);
WIRE 17 -1 (-2800 1200)(-2800 1250);
WIRE 17 -1 (-2800 1150)(-2800 1200);
WIRE 17 -1 (-2800 1100)(-2800 1150);
WIRE 17 -1 (-2800 1050)(-2800 1100);
WIRE 17 -1 (-2800 1000)(-2800 1050);
WIRE 17 -1 (-2800 1600)(-2800 1625);
WIRE 17 -1 (-2800 1550)(-2800 1600);
WIRE 17 -1 (-2050 1625)(-2800 1625);
FORCEPROP 2 LAST SIG_NAME M_L_ODT<3:0>
J 0
(-2700 1635);
DISPLAY 0.617021 (-2700 1635);
PAINT ORANGE (-2700 1635);
WIRE 17 -1 (-2800 1500)(-2800 1550);
WIRE 17 -1 (-2800 1450)(-2800 1500);
WIRE 17 -1 (-5625 4700)(-5625 4800);
WIRE 17 -1 (-5625 4650)(-5625 4700);
WIRE 17 -1 (-5625 4800)(-6375 4800);
FORCEPROP 2 LAST SIG_NAME M_L_DQ<63:0>
J 0
(-6325 4810);
DISPLAY 0.617021 (-6325 4810);
PAINT ORANGE (-6325 4810);
WIRE 17 -1 (-5625 4600)(-5625 4650);
WIRE 17 -1 (-5625 4550)(-5625 4600);
WIRE 17 -1 (-5625 4500)(-5625 4550);
WIRE 17 -1 (-5625 4450)(-5625 4500);
WIRE 17 -1 (-5625 4400)(-5625 4450);
WIRE 17 -1 (-5625 4350)(-5625 4400);
WIRE 17 -1 (-5625 4300)(-5625 4350);
WIRE 17 -1 (-5625 4250)(-5625 4300);
WIRE 17 -1 (-5625 4200)(-5625 4250);
WIRE 17 -1 (-5625 4150)(-5625 4200);
WIRE 17 -1 (-5625 4100)(-5625 4150);
WIRE 17 -1 (-5625 4050)(-5625 4100);
WIRE 17 -1 (-5625 4000)(-5625 4050);
WIRE 17 -1 (-5625 3950)(-5625 4000);
WIRE 17 -1 (-5625 3900)(-5625 3950);
WIRE 17 -1 (-5625 3850)(-5625 3900);
WIRE 17 -1 (-5625 3800)(-5625 3850);
WIRE 17 -1 (-5625 3750)(-5625 3800);
WIRE 17 -1 (-5625 3700)(-5625 3750);
WIRE 17 -1 (-5625 3650)(-5625 3700);
WIRE 17 -1 (-5625 3600)(-5625 3650);
WIRE 17 -1 (-5625 3550)(-5625 3600);
WIRE 17 -1 (-5625 3500)(-5625 3550);
WIRE 17 -1 (-5625 3450)(-5625 3500);
WIRE 17 -1 (-5625 3400)(-5625 3450);
WIRE 17 -1 (-5625 3350)(-5625 3400);
WIRE 17 -1 (-5625 3300)(-5625 3350);
WIRE 17 -1 (-5625 3250)(-5625 3300);
WIRE 17 -1 (-5625 3200)(-5625 3250);
WIRE 17 -1 (-5625 3150)(-5625 3200);
WIRE 17 -1 (-5625 3100)(-5625 3150);
WIRE 17 -1 (-5625 3050)(-5625 3100);
WIRE 17 -1 (-5625 3000)(-5625 3050);
WIRE 17 -1 (-5625 2950)(-5625 3000);
WIRE 17 -1 (-5625 2900)(-5625 2950);
WIRE 17 -1 (-5625 2850)(-5625 2900);
WIRE 17 -1 (-5625 2800)(-5625 2850);
WIRE 17 -1 (-5625 2750)(-5625 2800);
WIRE 17 -1 (-5625 2700)(-5625 2750);
WIRE 17 -1 (-5625 2650)(-5625 2700);
WIRE 17 -1 (-5625 2600)(-5625 2650);
WIRE 17 -1 (-5625 2550)(-5625 2600);
WIRE 17 -1 (-5625 2500)(-5625 2550);
WIRE 17 -1 (-5625 2450)(-5625 2500);
WIRE 17 -1 (-5625 2400)(-5625 2450);
WIRE 17 -1 (-5625 2350)(-5625 2400);
WIRE 17 -1 (-5625 2300)(-5625 2350);
WIRE 17 -1 (-5625 2250)(-5625 2300);
WIRE 17 -1 (-5625 2200)(-5625 2250);
WIRE 17 -1 (-5625 2150)(-5625 2200);
WIRE 17 -1 (-5625 2100)(-5625 2150);
WIRE 17 -1 (-5625 2050)(-5625 2100);
WIRE 17 -1 (-5625 2000)(-5625 2050);
WIRE 17 -1 (-5625 1950)(-5625 2000);
WIRE 17 -1 (-5625 1900)(-5625 1950);
WIRE 17 -1 (-5625 1850)(-5625 1900);
WIRE 17 -1 (-5625 1800)(-5625 1850);
WIRE 17 -1 (-5625 1750)(-5625 1800);
WIRE 17 -1 (-5625 1700)(-5625 1750);
WIRE 17 -1 (-5625 1650)(-5625 1700);
WIRE 17 -1 (-5625 1600)(-5625 1650);
WIRE 17 -1 (-5625 1550)(-5625 1600);
WIRE 17 -1 (-5625 800)(-5625 825);
WIRE 17 -1 (-5625 750)(-5625 800);
WIRE 17 -1 (-5625 825)(-6375 825);
FORCEPROP 2 LAST SIG_NAME M_L_CLK_DN<3:0>
J 0
(-6325 835);
DISPLAY 0.617021 (-6325 835);
PAINT ORANGE (-6325 835);
WIRE 17 -1 (-5625 700)(-5625 750);
WIRE 17 -1 (-5625 650)(-5625 700);
WIRE 17 -1 (-5625 1000)(-5625 1025);
WIRE 17 -1 (-5625 950)(-5625 1000);
WIRE 17 -1 (-5625 1025)(-6375 1025);
FORCEPROP 2 LAST SIG_NAME M_L_CLK_DP<3:0>
J 0
(-6325 1035);
DISPLAY 0.617021 (-6325 1035);
PAINT ORANGE (-6325 1035);
WIRE 17 -1 (-5625 900)(-5625 950);
WIRE 17 -1 (-5625 850)(-5625 900);
WIRE 17 -1 (-5625 1450)(-5625 1475);
WIRE 17 -1 (-5625 1400)(-5625 1450);
WIRE 17 -1 (-5625 1475)(-6375 1475);
FORCEPROP 2 LAST SIG_NAME M_L_ECC<7:0>
J 0
(-6325 1485);
DISPLAY 0.617021 (-6325 1485);
PAINT ORANGE (-6325 1485);
WIRE 17 -1 (-5625 1350)(-5625 1400);
WIRE 17 -1 (-5625 1300)(-5625 1350);
WIRE 17 -1 (-5625 1250)(-5625 1300);
WIRE 17 -1 (-5625 1200)(-5625 1250);
WIRE 17 -1 (-5625 1150)(-5625 1200);
WIRE 17 -1 (-5625 1100)(-5625 1150);
WIRE 16 -1 (-5025 525)(-6375 525);
FORCEPROP 2 LAST SIG_NAME M_L_C<2>
J 0
(-6325 535);
DISPLAY 0.617021 (-6325 535);
PAINT ORANGE (-6325 535);
WIRE 16 -1 (-5025 1075)(-5525 1075);
WIRE 16 -1 (-5025 1125)(-5525 1125);
WIRE 16 -1 (-5025 1175)(-5525 1175);
WIRE 16 -1 (-5025 1225)(-5525 1225);
WIRE 16 -1 (-5025 1275)(-5525 1275);
WIRE 16 -1 (-5025 1325)(-5525 1325);
WIRE 16 -1 (-5025 1375)(-5525 1375);
WIRE 16 -1 (-5025 1425)(-5525 1425);
WIRE 16 -1 (-5525 1525)(-5025 1525);
WIRE 16 -1 (-5525 1575)(-5025 1575);
WIRE 16 -1 (-5525 1625)(-5025 1625);
WIRE 16 -1 (-5025 1675)(-5525 1675);
WIRE 16 -1 (-5525 1725)(-5025 1725);
WIRE 16 -1 (-5525 1775)(-5025 1775);
WIRE 16 -1 (-5025 1825)(-5525 1825);
WIRE 16 -1 (-5525 1875)(-5025 1875);
WIRE 16 -1 (-5525 1925)(-5025 1925);
WIRE 16 -1 (-5525 1975)(-5025 1975);
WIRE 16 -1 (-5525 2025)(-5025 2025);
WIRE 16 -1 (-5025 825)(-5525 825);
WIRE 16 -1 (-5025 875)(-5525 875);
WIRE 16 -1 (-5025 925)(-5525 925);
WIRE 16 -1 (-5025 975)(-5525 975);
WIRE 16 -1 (-5025 625)(-5525 625);
WIRE 16 -1 (-5025 675)(-5525 675);
WIRE 16 -1 (-5025 725)(-5525 725);
WIRE 16 -1 (-5025 775)(-5525 775);
WIRE 16 -1 (-5525 2075)(-5025 2075);
WIRE 16 -1 (-5525 2125)(-5025 2125);
WIRE 16 -1 (-5525 2175)(-5025 2175);
WIRE 16 -1 (-5525 2225)(-5025 2225);
WIRE 16 -1 (-5025 2275)(-5525 2275);
WIRE 16 -1 (-5525 2325)(-5025 2325);
WIRE 16 -1 (-5525 2375)(-5025 2375);
WIRE 16 -1 (-5025 2425)(-5525 2425);
WIRE 16 -1 (-5525 2475)(-5025 2475);
WIRE 16 -1 (-5525 2525)(-5025 2525);
WIRE 16 -1 (-5525 2575)(-5025 2575);
WIRE 16 -1 (-5525 2625)(-5025 2625);
WIRE 16 -1 (-5025 2675)(-5525 2675);
WIRE 16 -1 (-5525 2725)(-5025 2725);
WIRE 16 -1 (-5525 2775)(-5025 2775);
WIRE 16 -1 (-5525 2825)(-5025 2825);
WIRE 16 -1 (-5525 2875)(-5025 2875);
WIRE 16 -1 (-5525 2925)(-5025 2925);
WIRE 16 -1 (-5525 2975)(-5025 2975);
WIRE 16 -1 (-5025 3025)(-5525 3025);
WIRE 16 -1 (-5525 3075)(-5025 3075);
WIRE 16 -1 (-5525 3125)(-5025 3125);
WIRE 16 -1 (-5525 3175)(-5025 3175);
WIRE 16 -1 (-5525 3225)(-5025 3225);
WIRE 16 -1 (-5525 3275)(-5025 3275);
WIRE 16 -1 (-5525 3325)(-5025 3325);
WIRE 16 -1 (-5025 3375)(-5525 3375);
WIRE 16 -1 (-5525 3425)(-5025 3425);
WIRE 16 -1 (-5525 3475)(-5025 3475);
WIRE 16 -1 (-5025 3525)(-5525 3525);
WIRE 16 -1 (-5525 3575)(-5025 3575);
WIRE 16 -1 (-5525 3625)(-5025 3625);
WIRE 16 -1 (-5025 3675)(-5525 3675);
WIRE 16 -1 (-5025 3725)(-5525 3725);
WIRE 16 -1 (-5025 3775)(-5525 3775);
WIRE 16 -1 (-5025 3825)(-5525 3825);
WIRE 16 -1 (-5025 3875)(-5525 3875);
WIRE 16 -1 (-5025 3925)(-5525 3925);
WIRE 16 -1 (-5025 3975)(-5525 3975);
WIRE 16 -1 (-5025 4025)(-5525 4025);
WIRE 16 -1 (-5025 4075)(-5525 4075);
WIRE 16 -1 (-5025 4125)(-5525 4125);
WIRE 16 -1 (-5025 4175)(-5525 4175);
WIRE 16 -1 (-5025 4225)(-5525 4225);
WIRE 16 -1 (-5025 4275)(-5525 4275);
WIRE 16 -1 (-5025 4325)(-5525 4325);
WIRE 16 -1 (-5025 4375)(-5525 4375);
WIRE 16 -1 (-5025 4425)(-5525 4425);
WIRE 16 -1 (-5025 4475)(-5525 4475);
WIRE 16 -1 (-5025 4525)(-5525 4525);
WIRE 16 -1 (-5025 4575)(-5525 4575);
WIRE 16 -1 (-5025 4625)(-5525 4625);
WIRE 16 -1 (-5025 4675)(-5525 4675);
WIRE 16 -1 (-3325 1425)(-2900 1425);
WIRE 16 -1 (-3325 1475)(-2900 1475);
WIRE 16 -1 (-3325 1525)(-2900 1525);
WIRE 16 -1 (-3325 1575)(-2900 1575);
WIRE 16 -1 (-3325 1925)(-2900 1925);
WIRE 16 -1 (-3325 1975)(-2900 1975);
WIRE 16 -1 (-3325 2025)(-2900 2025);
WIRE 16 -1 (-3325 975)(-2900 975);
WIRE 16 -1 (-3325 1025)(-2900 1025);
WIRE 16 -1 (-3325 1075)(-2900 1075);
WIRE 16 -1 (-3325 1125)(-2900 1125);
WIRE 16 -1 (-3325 1175)(-2900 1175);
WIRE 16 -1 (-3325 1225)(-2900 1225);
WIRE 16 -1 (-3325 1275)(-2900 1275);
WIRE 16 -1 (-3325 1325)(-2900 1325);
WIRE 16 -1 (-3325 1675)(-2900 1675);
WIRE 16 -1 (-3325 1725)(-2900 1725);
WIRE 16 -1 (-3325 1775)(-2900 1775);
WIRE 16 -1 (-3325 1825)(-2900 1825);
WIRE 16 -1 (-3325 825)(-2900 825);
WIRE 16 -1 (-3325 875)(-2900 875);
WIRE 16 -1 (-3325 725)(-2900 725);
WIRE 16 -1 (-3325 775)(-2900 775);
WIRE 16 -1 (-3325 2075)(-2900 2075);
WIRE 16 -1 (-3325 2125)(-2900 2125);
WIRE 16 -1 (-3325 2175)(-2900 2175);
WIRE 16 -1 (-3325 2225)(-2900 2225);
WIRE 16 -1 (-3325 2275)(-2900 2275);
WIRE 16 -1 (-3325 2325)(-2900 2325);
WIRE 16 -1 (-3325 2375)(-2900 2375);
WIRE 16 -1 (-3325 2425)(-2900 2425);
WIRE 16 -1 (-3325 2475)(-2900 2475);
WIRE 16 -1 (-3325 2525)(-2900 2525);
WIRE 16 -1 (-3325 2575)(-2900 2575);
WIRE 16 -1 (-3325 2625)(-2900 2625);
WIRE 16 -1 (-3325 2675)(-2900 2675);
WIRE 16 -1 (-3325 2725)(-2900 2725);
WIRE 16 -1 (-3325 2775)(-2900 2775);
WIRE 16 -1 (-3325 3825)(-2900 3825);
WIRE 16 -1 (-3325 3875)(-2900 3875);
WIRE 16 -1 (-3325 3925)(-2900 3925);
WIRE 16 -1 (-3325 3975)(-2900 3975);
WIRE 16 -1 (-3325 4025)(-2900 4025);
WIRE 16 -1 (-3325 4075)(-2900 4075);
WIRE 16 -1 (-3325 2875)(-2900 2875);
WIRE 16 -1 (-3325 2925)(-2900 2925);
WIRE 16 -1 (-3325 2975)(-2900 2975);
WIRE 16 -1 (-3325 3025)(-2900 3025);
WIRE 16 -1 (-3325 3075)(-2900 3075);
WIRE 16 -1 (-3325 3125)(-2900 3125);
WIRE 16 -1 (-3325 3175)(-2900 3175);
WIRE 16 -1 (-3325 3225)(-2900 3225);
WIRE 16 -1 (-3325 3275)(-2900 3275);
WIRE 16 -1 (-3325 3325)(-2900 3325);
WIRE 16 -1 (-3325 3375)(-2900 3375);
WIRE 16 -1 (-3325 3425)(-2900 3425);
WIRE 16 -1 (-3325 3475)(-2900 3475);
WIRE 16 -1 (-3325 3525)(-2900 3525);
WIRE 16 -1 (-3325 3575)(-2900 3575);
WIRE 16 -1 (-3325 3625)(-2900 3625);
WIRE 16 -1 (-3325 3675)(-2900 3675);
WIRE 16 -1 (-3325 3725)(-2900 3725);
WIRE 16 -1 (-2025 525)(-3325 525);
FORCEPROP 2 LAST SIG_NAME M_L_PAR
J 0
(-2700 535);
DISPLAY 0.617021 (-2700 535);
PAINT ORANGE (-2700 535);
WIRE 16 -1 (-2025 575)(-3325 575);
FORCEPROP 2 LAST SIG_NAME M_L_ALERT_N
J 0
(-2700 585);
DISPLAY 0.617021 (-2700 585);
PAINT ORANGE (-2700 585);
WIRE 16 -1 (-2025 625)(-3325 625);
FORCEPROP 2 LAST SIG_NAME M_L_ACT_N
J 0
(-2700 635);
DISPLAY 0.617021 (-2700 635);
PAINT ORANGE (-2700 635);
WIRE 16 -1 (-3325 4125)(-2900 4125);
WIRE 16 -1 (-3325 4175)(-2900 4175);
WIRE 16 -1 (-3325 4225)(-2900 4225);
WIRE 16 -1 (-3325 4275)(-2900 4275);
WIRE 16 -1 (-3325 4325)(-2900 4325);
WIRE 16 -1 (-3325 4375)(-2900 4375);
WIRE 16 -1 (-3325 4425)(-2900 4425);
WIRE 16 -1 (-3325 4475)(-2900 4475);
WIRE 16 -1 (-3325 4525)(-2900 4525);
WIRE 16 -1 (-3325 4575)(-2900 4575);
WIRE 16 -1 (-3325 4625)(-2900 4625);
WIRE 16 -1 (-3325 4675)(-2900 4675);
FORCENOTE
BOM_COST=PROC_SOCKET
(-7925 250) 0;
DISPLAY LEFT (-7925 250);
DISPLAY 1.723404 (-7925 250);
PAINT PURPLE (-7925 250);
FORCENOTE
ROOM=CPU1
(-7925 375) 0;
DISPLAY LEFT (-7925 375);
DISPLAY 1.723404 (-7925 375);
PAINT PURPLE (-7925 375);
QUIT
